FILE_TYPE = MACRO_DRAWING;
SET COLOR_WIRE YELLOW;
SET COLOR_PROP MONO;
SET COLOR_DOT WHITE;
SET COLOR_ARC YELLOW;
SET COLOR_BODY GREEN;
SET COLOR_NOTE MONO;
SET PROP_DISPLAY VALUE;
SET PAGE_NUMBER P106;
FORCEADD CAP..1
R 2
(-4100 2650);
FORCEPROP 1 LAST LOCATION C1R2
J 2
(-4150 2750);
DISPLAY 0.617021 (-4150 2750);
PAINT AQUA (-4150 2750);
FORCEPROP 1 LAST PART_NUMBER A36096-155
J 2
(-4150 2500);
DISPLAY 0.617021 (-4150 2500);
PAINT BLUE (-4150 2500);
FORCEPROP 1 LAST VALUE 0.22UF
J 2
(-4150 2700);
DISPLAY 0.617021 (-4150 2700);
PAINT SKYBLUE (-4150 2700);
FORCEPROP 1 LAST TOLERANCE 10%
J 2
(-4150 2600);
DISPLAY 0.617021 (-4150 2600);
PAINT SKYBLUE (-4150 2600);
FORCEPROP 1 LAST PACK_TYPE 0402
J 2
(-4150 2450);
DISPLAY 0.617021 (-4150 2450);
PAINT SKYBLUE (-4150 2450);
FORCEPROP 1 LAST VOLTAGE 16V
J 2
(-4150 2650);
DISPLAY 0.617021 (-4150 2650);
PAINT SKYBLUE (-4150 2650);
FORCEPROP 1 LAST MATERIAL X7R
J 2
(-4150 2550);
DISPLAY 0.617021 (-4150 2550);
PAINT SKYBLUE (-4150 2550);
FORCEPROP 2 LAST BOM_COST IO_SLOT
J 0
(-4350 2800);
PAINT MONO (-4350 2800);
DISPLAY INVISIBLE (-4350 2800);
FORCEPROP 2 LAST CDS_LIB mstr_discrete
J 0
(-4100 2650);
PAINT ORANGE (-4100 2650);
DISPLAY INVISIBLE (-4100 2650);
FORCEPROP 0 LAST CDS_SEC 1
J 0
(-4150 2800);
PAINT ORANGE (-4150 2800);
DISPLAY INVISIBLE (-4150 2800);
FORCEPROP 2 LAST $SEC 1
J 0
(-4150 2850);
DISPLAY 0.680851 (-4150 2850);
PAINT MONO (-4150 2850);
DISPLAY INVISIBLE (-4150 2850);
FORCEPROP 2 LAST CDS_LOCATION C1R2
J 2
(-4150 2750);
DISPLAY 0.617021 (-4150 2750);
PAINT AQUA (-4150 2750);
DISPLAY INVISIBLE (-4150 2750);
FORCEPROP 1 LAST PATH I10
J 2
(-4150 2800);
DISPLAY 0.978723 (-4150 2800);
PAINT WHITE (-4150 2800);
DISPLAY INVISIBLE (-4150 2800);
FORCEPROP 2 LAST ROOM PCIE_STEERING
J 2
(-4100 2650);
PAINT MONO (-4100 2650);
DISPLAY INVISIBLE (-4100 2650);
FORCEPROP 1 LASTPIN (-4100 2550) $PN 2
J 2
(-4110 2530);
DISPLAY 0.787234 (-4110 2530);
PAINT ORANGE (-4110 2530);
DISPLAY INVISIBLE (-4110 2530);
FORCEPROP 1 LASTPIN (-4100 2750) $PN 1
J 2
(-4110 2730);
DISPLAY 0.787234 (-4110 2730);
PAINT ORANGE (-4110 2730);
DISPLAY INVISIBLE (-4110 2730);
FORCEADD CAP..1
R 2
(-6500 2650);
FORCEPROP 1 LAST LOCATION C1M12
J 2
(-6550 2750);
DISPLAY 0.617021 (-6550 2750);
PAINT AQUA (-6550 2750);
FORCEPROP 1 LAST PART_NUMBER A36096-155
J 2
(-6550 2500);
DISPLAY 0.617021 (-6550 2500);
PAINT BLUE (-6550 2500);
FORCEPROP 1 LAST VALUE 0.22UF
J 2
(-6550 2700);
DISPLAY 0.617021 (-6550 2700);
PAINT SKYBLUE (-6550 2700);
FORCEPROP 1 LAST TOLERANCE 10%
J 2
(-6550 2600);
DISPLAY 0.617021 (-6550 2600);
PAINT SKYBLUE (-6550 2600);
FORCEPROP 1 LAST PACK_TYPE 0402
J 2
(-6550 2450);
DISPLAY 0.617021 (-6550 2450);
PAINT SKYBLUE (-6550 2450);
FORCEPROP 1 LAST VOLTAGE 16V
J 2
(-6550 2650);
DISPLAY 0.617021 (-6550 2650);
PAINT SKYBLUE (-6550 2650);
FORCEPROP 1 LAST MATERIAL X7R
J 2
(-6550 2550);
DISPLAY 0.617021 (-6550 2550);
PAINT SKYBLUE (-6550 2550);
FORCEPROP 2 LAST CDS_LIB mstr_discrete
J 0
(-6500 2650);
PAINT ORANGE (-6500 2650);
DISPLAY INVISIBLE (-6500 2650);
FORCEPROP 2 LAST BOM_COST IO_SLOT
J 0
(-6750 2800);
PAINT MONO (-6750 2800);
DISPLAY INVISIBLE (-6750 2800);
FORCEPROP 0 LAST CDS_SEC 1
J 0
(-6550 2800);
PAINT ORANGE (-6550 2800);
DISPLAY INVISIBLE (-6550 2800);
FORCEPROP 2 LAST $SEC 1
J 0
(-6550 2850);
DISPLAY 0.680851 (-6550 2850);
PAINT MONO (-6550 2850);
DISPLAY INVISIBLE (-6550 2850);
FORCEPROP 2 LAST CDS_LOCATION C1M12
J 2
(-6550 2750);
DISPLAY 0.617021 (-6550 2750);
PAINT AQUA (-6550 2750);
DISPLAY INVISIBLE (-6550 2750);
FORCEPROP 1 LAST PATH I100
J 2
(-6550 2800);
DISPLAY 0.978723 (-6550 2800);
PAINT WHITE (-6550 2800);
DISPLAY INVISIBLE (-6550 2800);
FORCEPROP 2 LAST ROOM PCIE_STEERING
J 2
(-6500 2650);
PAINT MONO (-6500 2650);
DISPLAY INVISIBLE (-6500 2650);
FORCEPROP 1 LASTPIN (-6500 2550) $PN 2
J 2
(-6510 2530);
DISPLAY 0.787234 (-6510 2530);
PAINT ORANGE (-6510 2530);
DISPLAY INVISIBLE (-6510 2530);
FORCEPROP 1 LASTPIN (-6500 2750) $PN 1
J 2
(-6510 2730);
DISPLAY 0.787234 (-6510 2730);
PAINT ORANGE (-6510 2730);
DISPLAY INVISIBLE (-6510 2730);
FORCEADD TAP..7
(-6500 2100);
FORCEPROP 3 LASTPIN (-6500 2150) SIG_NAME P3E_OCP_CPU0_PE3_C_TXP<12>
J 0
(-6490 2160);
DISPLAY 0.659574 (-6490 2160);
PAINT MONO (-6490 2160);
DISPLAY INVISIBLE (-6490 2160);
FORCEPROP 1 LASTPIN (-6500 2150) BN 12
R 1
J 0
(-6507 2098);
DISPLAY 0.617021 (-6507 2098);
PAINT GREEN (-6507 2098);
FORCEPROP 2 LAST CDS_LIB mstr_standard
J 0
(-6500 2100);
PAINT ORANGE (-6500 2100);
DISPLAY INVISIBLE (-6500 2100);
FORCEPROP 1 LAST BODY_TYPE PLUMBING
J 0
(-6450 2100);
DISPLAY 2.276596 (-6450 2100);
PAINT GREEN (-6450 2100);
DISPLAY INVISIBLE (-6450 2100);
FORCEPROP 1 LAST HDL_TAP TRUE
J 0
(-6180 1970);
DISPLAY 2.276596 (-6180 1970);
PAINT GREEN (-6180 1970);
DISPLAY INVISIBLE (-6180 1970);
FORCEPROP 1 LAST PATH I101
J 0
(-6502 2100);
DISPLAY 0.872340 (-6502 2100);
PAINT GREEN (-6502 2100);
DISPLAY INVISIBLE (-6502 2100);
FORCEADD CAP..1
R 2
(-6700 2350);
FORCEPROP 1 LAST LOCATION C1M10
J 2
(-6750 2450);
DISPLAY 0.617021 (-6750 2450);
PAINT AQUA (-6750 2450);
FORCEPROP 1 LAST PART_NUMBER A36096-155
J 2
(-6750 2200);
DISPLAY 0.617021 (-6750 2200);
PAINT BLUE (-6750 2200);
FORCEPROP 1 LAST VALUE 0.22UF
J 2
(-6750 2400);
DISPLAY 0.617021 (-6750 2400);
PAINT SKYBLUE (-6750 2400);
FORCEPROP 1 LAST TOLERANCE 10%
J 2
(-6750 2300);
DISPLAY 0.617021 (-6750 2300);
PAINT SKYBLUE (-6750 2300);
FORCEPROP 1 LAST PACK_TYPE 0402
J 2
(-6750 2150);
DISPLAY 0.617021 (-6750 2150);
PAINT SKYBLUE (-6750 2150);
FORCEPROP 1 LAST VOLTAGE 16V
J 2
(-6750 2350);
DISPLAY 0.617021 (-6750 2350);
PAINT SKYBLUE (-6750 2350);
FORCEPROP 1 LAST MATERIAL X7R
J 2
(-6750 2250);
DISPLAY 0.617021 (-6750 2250);
PAINT SKYBLUE (-6750 2250);
FORCEPROP 2 LAST CDS_LIB mstr_discrete
J 0
(-6700 2350);
PAINT ORANGE (-6700 2350);
DISPLAY INVISIBLE (-6700 2350);
FORCEPROP 2 LAST BOM_COST IO_SLOT
J 0
(-6950 2500);
PAINT MONO (-6950 2500);
DISPLAY INVISIBLE (-6950 2500);
FORCEPROP 0 LAST CDS_SEC 1
J 0
(-6750 2500);
PAINT ORANGE (-6750 2500);
DISPLAY INVISIBLE (-6750 2500);
FORCEPROP 2 LAST $SEC 1
J 0
(-6750 2550);
DISPLAY 0.680851 (-6750 2550);
PAINT MONO (-6750 2550);
DISPLAY INVISIBLE (-6750 2550);
FORCEPROP 2 LAST CDS_LOCATION C1M10
J 2
(-6750 2450);
DISPLAY 0.617021 (-6750 2450);
PAINT AQUA (-6750 2450);
DISPLAY INVISIBLE (-6750 2450);
FORCEPROP 1 LAST PATH I102
J 2
(-6750 2500);
DISPLAY 0.978723 (-6750 2500);
PAINT WHITE (-6750 2500);
DISPLAY INVISIBLE (-6750 2500);
FORCEPROP 2 LAST ROOM PCIE_STEERING
J 2
(-6700 2350);
PAINT MONO (-6700 2350);
DISPLAY INVISIBLE (-6700 2350);
FORCEPROP 1 LASTPIN (-6700 2250) $PN 2
J 2
(-6710 2230);
DISPLAY 0.787234 (-6710 2230);
PAINT ORANGE (-6710 2230);
DISPLAY INVISIBLE (-6710 2230);
FORCEPROP 1 LASTPIN (-6700 2450) $PN 1
J 2
(-6710 2430);
DISPLAY 0.787234 (-6710 2430);
PAINT ORANGE (-6710 2430);
DISPLAY INVISIBLE (-6710 2430);
FORCEADD TAP..7
(-6700 2100);
FORCEPROP 3 LASTPIN (-6700 2150) SIG_NAME P3E_OCP_CPU0_PE3_C_TXP<13>
J 0
(-6690 2160);
DISPLAY 0.659574 (-6690 2160);
PAINT MONO (-6690 2160);
DISPLAY INVISIBLE (-6690 2160);
FORCEPROP 1 LASTPIN (-6700 2150) BN 13
R 1
J 0
(-6707 2098);
DISPLAY 0.617021 (-6707 2098);
PAINT GREEN (-6707 2098);
FORCEPROP 2 LAST CDS_LIB mstr_standard
J 0
(-6700 2100);
PAINT ORANGE (-6700 2100);
DISPLAY INVISIBLE (-6700 2100);
FORCEPROP 1 LAST BODY_TYPE PLUMBING
J 0
(-6650 2100);
DISPLAY 2.276596 (-6650 2100);
PAINT GREEN (-6650 2100);
DISPLAY INVISIBLE (-6650 2100);
FORCEPROP 1 LAST HDL_TAP TRUE
J 0
(-6380 1970);
DISPLAY 2.276596 (-6380 1970);
PAINT GREEN (-6380 1970);
DISPLAY INVISIBLE (-6380 1970);
FORCEPROP 1 LAST PATH I103
J 0
(-6702 2100);
DISPLAY 0.872340 (-6702 2100);
PAINT GREEN (-6702 2100);
DISPLAY INVISIBLE (-6702 2100);
FORCEADD TAP..7
(-6900 2100);
FORCEPROP 3 LASTPIN (-6900 2150) SIG_NAME P3E_OCP_CPU0_PE3_C_TXP<14>
J 0
(-6890 2160);
DISPLAY 0.659574 (-6890 2160);
PAINT MONO (-6890 2160);
DISPLAY INVISIBLE (-6890 2160);
FORCEPROP 1 LASTPIN (-6900 2150) BN 14
R 1
J 0
(-6907 2098);
DISPLAY 0.617021 (-6907 2098);
PAINT GREEN (-6907 2098);
FORCEPROP 2 LAST CDS_LIB mstr_standard
J 0
(-6900 2100);
PAINT ORANGE (-6900 2100);
DISPLAY INVISIBLE (-6900 2100);
FORCEPROP 1 LAST BODY_TYPE PLUMBING
J 0
(-6850 2100);
DISPLAY 2.276596 (-6850 2100);
PAINT GREEN (-6850 2100);
DISPLAY INVISIBLE (-6850 2100);
FORCEPROP 1 LAST HDL_TAP TRUE
J 0
(-6580 1970);
DISPLAY 2.276596 (-6580 1970);
PAINT GREEN (-6580 1970);
DISPLAY INVISIBLE (-6580 1970);
FORCEPROP 1 LAST PATH I104
J 0
(-6902 2100);
DISPLAY 0.872340 (-6902 2100);
PAINT GREEN (-6902 2100);
DISPLAY INVISIBLE (-6902 2100);
FORCEADD CAP..1
R 2
(-6900 2650);
FORCEPROP 1 LAST LOCATION C1M8
J 2
(-6950 2750);
DISPLAY 0.617021 (-6950 2750);
PAINT AQUA (-6950 2750);
FORCEPROP 1 LAST PART_NUMBER A36096-155
J 2
(-6950 2500);
DISPLAY 0.617021 (-6950 2500);
PAINT BLUE (-6950 2500);
FORCEPROP 1 LAST VALUE 0.22UF
J 2
(-6950 2700);
DISPLAY 0.617021 (-6950 2700);
PAINT SKYBLUE (-6950 2700);
FORCEPROP 1 LAST TOLERANCE 10%
J 2
(-6950 2600);
DISPLAY 0.617021 (-6950 2600);
PAINT SKYBLUE (-6950 2600);
FORCEPROP 1 LAST PACK_TYPE 0402
J 2
(-6950 2450);
DISPLAY 0.617021 (-6950 2450);
PAINT SKYBLUE (-6950 2450);
FORCEPROP 1 LAST VOLTAGE 16V
J 2
(-6950 2650);
DISPLAY 0.617021 (-6950 2650);
PAINT SKYBLUE (-6950 2650);
FORCEPROP 1 LAST MATERIAL X7R
J 2
(-6950 2550);
DISPLAY 0.617021 (-6950 2550);
PAINT SKYBLUE (-6950 2550);
FORCEPROP 2 LAST CDS_LIB mstr_discrete
J 0
(-6900 2650);
PAINT ORANGE (-6900 2650);
DISPLAY INVISIBLE (-6900 2650);
FORCEPROP 0 LAST CDS_SEC 1
J 0
(-6950 2800);
PAINT ORANGE (-6950 2800);
DISPLAY INVISIBLE (-6950 2800);
FORCEPROP 2 LAST $SEC 1
J 0
(-6950 2850);
DISPLAY 0.680851 (-6950 2850);
PAINT MONO (-6950 2850);
DISPLAY INVISIBLE (-6950 2850);
FORCEPROP 2 LAST CDS_LOCATION C1M8
J 2
(-6950 2750);
DISPLAY 0.617021 (-6950 2750);
PAINT AQUA (-6950 2750);
DISPLAY INVISIBLE (-6950 2750);
FORCEPROP 1 LAST PATH I105
J 2
(-6950 2800);
DISPLAY 0.978723 (-6950 2800);
PAINT WHITE (-6950 2800);
DISPLAY INVISIBLE (-6950 2800);
FORCEPROP 2 LAST ROOM PCIE_STEERING
J 2
(-6900 2650);
PAINT MONO (-6900 2650);
DISPLAY INVISIBLE (-6900 2650);
FORCEPROP 1 LASTPIN (-6900 2550) $PN 2
J 2
(-6910 2530);
DISPLAY 0.787234 (-6910 2530);
PAINT ORANGE (-6910 2530);
DISPLAY INVISIBLE (-6910 2530);
FORCEPROP 1 LASTPIN (-6900 2750) $PN 1
J 2
(-6910 2730);
DISPLAY 0.787234 (-6910 2730);
PAINT ORANGE (-6910 2730);
DISPLAY INVISIBLE (-6910 2730);
FORCEADD TAP..3
(-7100 2900);
FORCEPROP 3 LASTPIN (-7100 2850) SIG_NAME P3E_CPU0_PE3_OCP_TXP<15>
J 0
(-7090 2860);
DISPLAY 0.659574 (-7090 2860);
PAINT MONO (-7090 2860);
DISPLAY INVISIBLE (-7090 2860);
FORCEPROP 1 LASTPIN (-7100 2850) BN 15
R 1
J 0
(-7107 2838);
DISPLAY 0.617021 (-7107 2838);
PAINT GREEN (-7107 2838);
FORCEPROP 2 LAST CDS_LIB mstr_standard
J 0
(-7100 2900);
PAINT ORANGE (-7100 2900);
DISPLAY INVISIBLE (-7100 2900);
FORCEPROP 1 LAST BODY_TYPE PLUMBING
J 0
(-7050 2850);
DISPLAY 2.276596 (-7050 2850);
PAINT GREEN (-7050 2850);
DISPLAY INVISIBLE (-7050 2850);
FORCEPROP 1 LAST HDL_TAP TRUE
J 0
(-6780 2770);
DISPLAY 2.276596 (-6780 2770);
PAINT GREEN (-6780 2770);
DISPLAY INVISIBLE (-6780 2770);
FORCEPROP 1 LAST PATH I106
J 0
(-7102 2900);
DISPLAY 0.872340 (-7102 2900);
PAINT GREEN (-7102 2900);
DISPLAY INVISIBLE (-7102 2900);
FORCEADD OFFPAGE..1
(-7275 2950);
FORCEPROP 2 LAST $XR0 32 
J 0
(-7496 2950);
DISPLAY 0.638298 (-7496 2950);
PAINT MONO (-7496 2950);
FORCEPROP 2 LAST CDS_LIB mstr_standard
J 0
(-7275 2950);
PAINT ORANGE (-7275 2950);
DISPLAY INVISIBLE (-7275 2950);
FORCEPROP 1 LAST OFFPAGE TRUE
J 0
(-6955 2820);
PAINT GREEN (-6955 2820);
DISPLAY INVISIBLE (-6955 2820);
FORCEPROP 1 LAST COMMENT_BODY TRUE
J 0
(-7155 2850);
DISPLAY 2.276596 (-7155 2850);
PAINT GREEN (-7155 2850);
DISPLAY INVISIBLE (-7155 2850);
FORCEPROP 2 LAST PATH I107
J 0
(-7525 3000);
DISPLAY 1.021277 (-7525 3000);
PAINT ORANGE (-7525 3000);
DISPLAY INVISIBLE (-7525 3000);
FORCEADD TAP..7
(-7100 2100);
FORCEPROP 3 LASTPIN (-7100 2150) SIG_NAME P3E_OCP_CPU0_PE3_C_TXP<15>
J 0
(-7090 2160);
DISPLAY 0.659574 (-7090 2160);
PAINT MONO (-7090 2160);
DISPLAY INVISIBLE (-7090 2160);
FORCEPROP 1 LASTPIN (-7100 2150) BN 15
R 1
J 0
(-7107 2098);
DISPLAY 0.617021 (-7107 2098);
PAINT GREEN (-7107 2098);
FORCEPROP 2 LAST CDS_LIB mstr_standard
J 0
(-7100 2100);
PAINT ORANGE (-7100 2100);
DISPLAY INVISIBLE (-7100 2100);
FORCEPROP 1 LAST BODY_TYPE PLUMBING
J 0
(-7050 2100);
DISPLAY 2.276596 (-7050 2100);
PAINT GREEN (-7050 2100);
DISPLAY INVISIBLE (-7050 2100);
FORCEPROP 1 LAST HDL_TAP TRUE
J 0
(-6780 1970);
DISPLAY 2.276596 (-6780 1970);
PAINT GREEN (-6780 1970);
DISPLAY INVISIBLE (-6780 1970);
FORCEPROP 1 LAST PATH I108
J 0
(-7102 2100);
DISPLAY 0.872340 (-7102 2100);
PAINT GREEN (-7102 2100);
DISPLAY INVISIBLE (-7102 2100);
FORCEADD CAP..1
R 2
(-7100 2350);
FORCEPROP 1 LAST LOCATION C1M6
J 2
(-7150 2450);
DISPLAY 0.617021 (-7150 2450);
PAINT AQUA (-7150 2450);
FORCEPROP 1 LAST PART_NUMBER A36096-155
J 2
(-7150 2200);
DISPLAY 0.617021 (-7150 2200);
PAINT BLUE (-7150 2200);
FORCEPROP 1 LAST VALUE 0.22UF
J 2
(-7150 2400);
DISPLAY 0.617021 (-7150 2400);
PAINT SKYBLUE (-7150 2400);
FORCEPROP 1 LAST TOLERANCE 10%
J 2
(-7150 2300);
DISPLAY 0.617021 (-7150 2300);
PAINT SKYBLUE (-7150 2300);
FORCEPROP 1 LAST PACK_TYPE 0402
J 2
(-7150 2150);
DISPLAY 0.617021 (-7150 2150);
PAINT SKYBLUE (-7150 2150);
FORCEPROP 1 LAST VOLTAGE 16V
J 2
(-7150 2350);
DISPLAY 0.617021 (-7150 2350);
PAINT SKYBLUE (-7150 2350);
FORCEPROP 1 LAST MATERIAL X7R
J 2
(-7150 2250);
DISPLAY 0.617021 (-7150 2250);
PAINT SKYBLUE (-7150 2250);
FORCEPROP 2 LAST CDS_LIB mstr_discrete
J 0
(-7100 2350);
PAINT ORANGE (-7100 2350);
DISPLAY INVISIBLE (-7100 2350);
FORCEPROP 0 LAST CDS_SEC 1
J 0
(-7150 2500);
PAINT ORANGE (-7150 2500);
DISPLAY INVISIBLE (-7150 2500);
FORCEPROP 2 LAST $SEC 1
J 0
(-7150 2550);
DISPLAY 0.680851 (-7150 2550);
PAINT MONO (-7150 2550);
DISPLAY INVISIBLE (-7150 2550);
FORCEPROP 2 LAST CDS_LOCATION C1M6
J 2
(-7150 2450);
DISPLAY 0.617021 (-7150 2450);
PAINT AQUA (-7150 2450);
DISPLAY INVISIBLE (-7150 2450);
FORCEPROP 1 LAST PATH I109
J 2
(-7150 2500);
DISPLAY 0.978723 (-7150 2500);
PAINT WHITE (-7150 2500);
DISPLAY INVISIBLE (-7150 2500);
FORCEPROP 2 LAST ROOM PCIE_STEERING
J 2
(-7100 2350);
PAINT MONO (-7100 2350);
DISPLAY INVISIBLE (-7100 2350);
FORCEPROP 1 LASTPIN (-7100 2250) $PN 2
J 2
(-7110 2230);
DISPLAY 0.787234 (-7110 2230);
PAINT ORANGE (-7110 2230);
DISPLAY INVISIBLE (-7110 2230);
FORCEPROP 1 LASTPIN (-7100 2450) $PN 1
J 2
(-7110 2430);
DISPLAY 0.787234 (-7110 2430);
PAINT ORANGE (-7110 2430);
DISPLAY INVISIBLE (-7110 2430);
FORCEADD TAP..3
(-4300 2900);
FORCEPROP 3 LASTPIN (-4300 2850) SIG_NAME P3E_CPU0_PE3_OCP_TXP<1>
J 0
(-4290 2860);
DISPLAY 0.659574 (-4290 2860);
PAINT MONO (-4290 2860);
DISPLAY INVISIBLE (-4290 2860);
FORCEPROP 1 LASTPIN (-4300 2850) BN 1
R 1
J 0
(-4307 2838);
DISPLAY 0.617021 (-4307 2838);
PAINT GREEN (-4307 2838);
FORCEPROP 2 LAST CDS_LIB mstr_standard
J 0
(-4300 2900);
PAINT ORANGE (-4300 2900);
DISPLAY INVISIBLE (-4300 2900);
FORCEPROP 1 LAST BODY_TYPE PLUMBING
J 0
(-4250 2850);
DISPLAY 2.276596 (-4250 2850);
PAINT GREEN (-4250 2850);
DISPLAY INVISIBLE (-4250 2850);
FORCEPROP 1 LAST HDL_TAP TRUE
J 0
(-3980 2770);
DISPLAY 2.276596 (-3980 2770);
PAINT GREEN (-3980 2770);
DISPLAY INVISIBLE (-3980 2770);
FORCEPROP 1 LAST PATH I11
J 0
(-4302 2900);
DISPLAY 0.872340 (-4302 2900);
PAINT GREEN (-4302 2900);
DISPLAY INVISIBLE (-4302 2900);
FORCEADD TAP..3
(-6450 1900);
FORCEPROP 3 LASTPIN (-6450 1850) SIG_NAME P3E_CPU0_PE3_OCP_TXN<12>
J 0
(-6440 1860);
DISPLAY 0.659574 (-6440 1860);
PAINT MONO (-6440 1860);
DISPLAY INVISIBLE (-6440 1860);
FORCEPROP 1 LASTPIN (-6450 1850) BN 12
R 1
J 0
(-6457 1838);
DISPLAY 0.617021 (-6457 1838);
PAINT GREEN (-6457 1838);
FORCEPROP 2 LAST CDS_LIB mstr_standard
J 0
(-6450 1900);
PAINT ORANGE (-6450 1900);
DISPLAY INVISIBLE (-6450 1900);
FORCEPROP 1 LAST BODY_TYPE PLUMBING
J 0
(-6400 1850);
DISPLAY 2.276596 (-6400 1850);
PAINT GREEN (-6400 1850);
DISPLAY INVISIBLE (-6400 1850);
FORCEPROP 1 LAST HDL_TAP TRUE
J 0
(-6130 1770);
DISPLAY 2.276596 (-6130 1770);
PAINT GREEN (-6130 1770);
DISPLAY INVISIBLE (-6130 1770);
FORCEPROP 1 LAST PATH I110
J 0
(-6452 1900);
DISPLAY 0.872340 (-6452 1900);
PAINT GREEN (-6452 1900);
DISPLAY INVISIBLE (-6452 1900);
FORCEADD CAP..1
R 2
(-6450 1650);
FORCEPROP 1 LAST LOCATION C1M13
J 2
(-6500 1750);
DISPLAY 0.617021 (-6500 1750);
PAINT AQUA (-6500 1750);
FORCEPROP 1 LAST PART_NUMBER A36096-155
J 2
(-6500 1500);
DISPLAY 0.617021 (-6500 1500);
PAINT BLUE (-6500 1500);
FORCEPROP 1 LAST VALUE 0.22UF
J 2
(-6500 1700);
DISPLAY 0.617021 (-6500 1700);
PAINT SKYBLUE (-6500 1700);
FORCEPROP 1 LAST TOLERANCE 10%
J 2
(-6500 1600);
DISPLAY 0.617021 (-6500 1600);
PAINT SKYBLUE (-6500 1600);
FORCEPROP 1 LAST PACK_TYPE 0402
J 2
(-6500 1450);
DISPLAY 0.617021 (-6500 1450);
PAINT SKYBLUE (-6500 1450);
FORCEPROP 1 LAST VOLTAGE 16V
J 2
(-6500 1650);
DISPLAY 0.617021 (-6500 1650);
PAINT SKYBLUE (-6500 1650);
FORCEPROP 1 LAST MATERIAL X7R
J 2
(-6500 1550);
DISPLAY 0.617021 (-6500 1550);
PAINT SKYBLUE (-6500 1550);
FORCEPROP 2 LAST CDS_LIB mstr_discrete
J 0
(-6450 1650);
PAINT ORANGE (-6450 1650);
DISPLAY INVISIBLE (-6450 1650);
FORCEPROP 2 LAST BOM_COST IO_SLOT
J 0
(-6700 1800);
PAINT MONO (-6700 1800);
DISPLAY INVISIBLE (-6700 1800);
FORCEPROP 0 LAST CDS_SEC 1
J 0
(-6500 1800);
PAINT ORANGE (-6500 1800);
DISPLAY INVISIBLE (-6500 1800);
FORCEPROP 2 LAST $SEC 1
J 0
(-6500 1850);
DISPLAY 0.680851 (-6500 1850);
PAINT MONO (-6500 1850);
DISPLAY INVISIBLE (-6500 1850);
FORCEPROP 2 LAST CDS_LOCATION C1M13
J 2
(-6500 1750);
DISPLAY 0.617021 (-6500 1750);
PAINT AQUA (-6500 1750);
DISPLAY INVISIBLE (-6500 1750);
FORCEPROP 1 LAST PATH I111
J 2
(-6500 1800);
DISPLAY 0.978723 (-6500 1800);
PAINT WHITE (-6500 1800);
DISPLAY INVISIBLE (-6500 1800);
FORCEPROP 2 LAST ROOM PCIE_STEERING
J 2
(-6450 1650);
PAINT MONO (-6450 1650);
DISPLAY INVISIBLE (-6450 1650);
FORCEPROP 1 LASTPIN (-6450 1550) $PN 2
J 2
(-6460 1530);
DISPLAY 0.787234 (-6460 1530);
PAINT ORANGE (-6460 1530);
DISPLAY INVISIBLE (-6460 1530);
FORCEPROP 1 LASTPIN (-6450 1750) $PN 1
J 2
(-6460 1730);
DISPLAY 0.787234 (-6460 1730);
PAINT ORANGE (-6460 1730);
DISPLAY INVISIBLE (-6460 1730);
FORCEADD TAP..3
(-6650 1900);
FORCEPROP 3 LASTPIN (-6650 1850) SIG_NAME P3E_CPU0_PE3_OCP_TXN<13>
J 0
(-6640 1860);
DISPLAY 0.659574 (-6640 1860);
PAINT MONO (-6640 1860);
DISPLAY INVISIBLE (-6640 1860);
FORCEPROP 1 LASTPIN (-6650 1850) BN 13
R 1
J 0
(-6657 1838);
DISPLAY 0.617021 (-6657 1838);
PAINT GREEN (-6657 1838);
FORCEPROP 2 LAST CDS_LIB mstr_standard
J 0
(-6650 1900);
PAINT ORANGE (-6650 1900);
DISPLAY INVISIBLE (-6650 1900);
FORCEPROP 1 LAST BODY_TYPE PLUMBING
J 0
(-6600 1850);
DISPLAY 2.276596 (-6600 1850);
PAINT GREEN (-6600 1850);
DISPLAY INVISIBLE (-6600 1850);
FORCEPROP 1 LAST HDL_TAP TRUE
J 0
(-6330 1770);
DISPLAY 2.276596 (-6330 1770);
PAINT GREEN (-6330 1770);
DISPLAY INVISIBLE (-6330 1770);
FORCEPROP 1 LAST PATH I112
J 0
(-6652 1900);
DISPLAY 0.872340 (-6652 1900);
PAINT GREEN (-6652 1900);
DISPLAY INVISIBLE (-6652 1900);
FORCEADD TAP..3
(-6850 1900);
FORCEPROP 3 LASTPIN (-6850 1850) SIG_NAME P3E_CPU0_PE3_OCP_TXN<14>
J 0
(-6840 1860);
DISPLAY 0.659574 (-6840 1860);
PAINT MONO (-6840 1860);
DISPLAY INVISIBLE (-6840 1860);
FORCEPROP 1 LASTPIN (-6850 1850) BN 14
R 1
J 0
(-6857 1838);
DISPLAY 0.617021 (-6857 1838);
PAINT GREEN (-6857 1838);
FORCEPROP 2 LAST CDS_LIB mstr_standard
J 0
(-6850 1900);
PAINT ORANGE (-6850 1900);
DISPLAY INVISIBLE (-6850 1900);
FORCEPROP 1 LAST BODY_TYPE PLUMBING
J 0
(-6800 1850);
DISPLAY 2.276596 (-6800 1850);
PAINT GREEN (-6800 1850);
DISPLAY INVISIBLE (-6800 1850);
FORCEPROP 1 LAST HDL_TAP TRUE
J 0
(-6530 1770);
DISPLAY 2.276596 (-6530 1770);
PAINT GREEN (-6530 1770);
DISPLAY INVISIBLE (-6530 1770);
FORCEPROP 1 LAST PATH I113
J 0
(-6852 1900);
DISPLAY 0.872340 (-6852 1900);
PAINT GREEN (-6852 1900);
DISPLAY INVISIBLE (-6852 1900);
FORCEADD CAP..1
R 2
(-6850 1650);
FORCEPROP 1 LAST LOCATION C1M9
J 2
(-6900 1750);
DISPLAY 0.617021 (-6900 1750);
PAINT AQUA (-6900 1750);
FORCEPROP 1 LAST PART_NUMBER A36096-155
J 2
(-6900 1500);
DISPLAY 0.617021 (-6900 1500);
PAINT BLUE (-6900 1500);
FORCEPROP 1 LAST VALUE 0.22UF
J 2
(-6900 1700);
DISPLAY 0.617021 (-6900 1700);
PAINT SKYBLUE (-6900 1700);
FORCEPROP 1 LAST TOLERANCE 10%
J 2
(-6900 1600);
DISPLAY 0.617021 (-6900 1600);
PAINT SKYBLUE (-6900 1600);
FORCEPROP 1 LAST PACK_TYPE 0402
J 2
(-6900 1450);
DISPLAY 0.617021 (-6900 1450);
PAINT SKYBLUE (-6900 1450);
FORCEPROP 1 LAST VOLTAGE 16V
J 2
(-6900 1650);
DISPLAY 0.617021 (-6900 1650);
PAINT SKYBLUE (-6900 1650);
FORCEPROP 1 LAST MATERIAL X7R
J 2
(-6900 1550);
DISPLAY 0.617021 (-6900 1550);
PAINT SKYBLUE (-6900 1550);
FORCEPROP 2 LAST CDS_LIB mstr_discrete
J 0
(-6850 1650);
PAINT ORANGE (-6850 1650);
DISPLAY INVISIBLE (-6850 1650);
FORCEPROP 0 LAST CDS_SEC 1
J 0
(-6900 1800);
PAINT ORANGE (-6900 1800);
DISPLAY INVISIBLE (-6900 1800);
FORCEPROP 2 LAST $SEC 1
J 0
(-6900 1850);
DISPLAY 0.680851 (-6900 1850);
PAINT MONO (-6900 1850);
DISPLAY INVISIBLE (-6900 1850);
FORCEPROP 2 LAST CDS_LOCATION C1M9
J 2
(-6900 1750);
DISPLAY 0.617021 (-6900 1750);
PAINT AQUA (-6900 1750);
DISPLAY INVISIBLE (-6900 1750);
FORCEPROP 1 LAST PATH I114
J 2
(-6900 1800);
DISPLAY 0.978723 (-6900 1800);
PAINT WHITE (-6900 1800);
DISPLAY INVISIBLE (-6900 1800);
FORCEPROP 2 LAST ROOM PCIE_STEERING
J 2
(-6850 1650);
PAINT MONO (-6850 1650);
DISPLAY INVISIBLE (-6850 1650);
FORCEPROP 1 LASTPIN (-6850 1550) $PN 2
J 2
(-6860 1530);
DISPLAY 0.787234 (-6860 1530);
PAINT ORANGE (-6860 1530);
DISPLAY INVISIBLE (-6860 1530);
FORCEPROP 1 LASTPIN (-6850 1750) $PN 1
J 2
(-6860 1730);
DISPLAY 0.787234 (-6860 1730);
PAINT ORANGE (-6860 1730);
DISPLAY INVISIBLE (-6860 1730);
FORCEADD TAP..7
(-6450 1100);
FORCEPROP 3 LASTPIN (-6450 1150) SIG_NAME P3E_OCP_CPU0_PE3_C_TXN<12>
J 0
(-6440 1160);
DISPLAY 0.659574 (-6440 1160);
PAINT MONO (-6440 1160);
DISPLAY INVISIBLE (-6440 1160);
FORCEPROP 1 LASTPIN (-6450 1150) BN 12
R 1
J 0
(-6457 1098);
DISPLAY 0.617021 (-6457 1098);
PAINT GREEN (-6457 1098);
FORCEPROP 2 LAST CDS_LIB mstr_standard
J 0
(-6450 1100);
PAINT ORANGE (-6450 1100);
DISPLAY INVISIBLE (-6450 1100);
FORCEPROP 1 LAST BODY_TYPE PLUMBING
J 0
(-6400 1100);
DISPLAY 2.276596 (-6400 1100);
PAINT GREEN (-6400 1100);
DISPLAY INVISIBLE (-6400 1100);
FORCEPROP 1 LAST HDL_TAP TRUE
J 0
(-6130 970);
DISPLAY 2.276596 (-6130 970);
PAINT GREEN (-6130 970);
DISPLAY INVISIBLE (-6130 970);
FORCEPROP 1 LAST PATH I115
J 0
(-6452 1100);
DISPLAY 0.872340 (-6452 1100);
PAINT GREEN (-6452 1100);
DISPLAY INVISIBLE (-6452 1100);
FORCEADD TAP..7
(-6650 1100);
FORCEPROP 3 LASTPIN (-6650 1150) SIG_NAME P3E_OCP_CPU0_PE3_C_TXN<13>
J 0
(-6640 1160);
DISPLAY 0.659574 (-6640 1160);
PAINT MONO (-6640 1160);
DISPLAY INVISIBLE (-6640 1160);
FORCEPROP 1 LASTPIN (-6650 1150) BN 13
R 1
J 0
(-6657 1098);
DISPLAY 0.617021 (-6657 1098);
PAINT GREEN (-6657 1098);
FORCEPROP 2 LAST CDS_LIB mstr_standard
J 0
(-6650 1100);
PAINT ORANGE (-6650 1100);
DISPLAY INVISIBLE (-6650 1100);
FORCEPROP 1 LAST BODY_TYPE PLUMBING
J 0
(-6600 1100);
DISPLAY 2.276596 (-6600 1100);
PAINT GREEN (-6600 1100);
DISPLAY INVISIBLE (-6600 1100);
FORCEPROP 1 LAST HDL_TAP TRUE
J 0
(-6330 970);
DISPLAY 2.276596 (-6330 970);
PAINT GREEN (-6330 970);
DISPLAY INVISIBLE (-6330 970);
FORCEPROP 1 LAST PATH I116
J 0
(-6652 1100);
DISPLAY 0.872340 (-6652 1100);
PAINT GREEN (-6652 1100);
DISPLAY INVISIBLE (-6652 1100);
FORCEADD CAP..1
R 2
(-6650 1350);
FORCEPROP 1 LAST LOCATION C1M11
J 2
(-6700 1450);
DISPLAY 0.617021 (-6700 1450);
PAINT AQUA (-6700 1450);
FORCEPROP 1 LAST PART_NUMBER A36096-155
J 2
(-6700 1200);
DISPLAY 0.617021 (-6700 1200);
PAINT BLUE (-6700 1200);
FORCEPROP 1 LAST VALUE 0.22UF
J 2
(-6700 1400);
DISPLAY 0.617021 (-6700 1400);
PAINT SKYBLUE (-6700 1400);
FORCEPROP 1 LAST TOLERANCE 10%
J 2
(-6700 1300);
DISPLAY 0.617021 (-6700 1300);
PAINT SKYBLUE (-6700 1300);
FORCEPROP 1 LAST PACK_TYPE 0402
J 2
(-6700 1150);
DISPLAY 0.617021 (-6700 1150);
PAINT SKYBLUE (-6700 1150);
FORCEPROP 1 LAST VOLTAGE 16V
J 2
(-6700 1350);
DISPLAY 0.617021 (-6700 1350);
PAINT SKYBLUE (-6700 1350);
FORCEPROP 1 LAST MATERIAL X7R
J 2
(-6700 1250);
DISPLAY 0.617021 (-6700 1250);
PAINT SKYBLUE (-6700 1250);
FORCEPROP 2 LAST CDS_LIB mstr_discrete
J 0
(-6650 1350);
PAINT ORANGE (-6650 1350);
DISPLAY INVISIBLE (-6650 1350);
FORCEPROP 2 LAST BOM_COST IO_SLOT
J 0
(-6900 1500);
PAINT MONO (-6900 1500);
DISPLAY INVISIBLE (-6900 1500);
FORCEPROP 0 LAST CDS_SEC 1
J 0
(-6700 1500);
PAINT ORANGE (-6700 1500);
DISPLAY INVISIBLE (-6700 1500);
FORCEPROP 2 LAST $SEC 1
J 0
(-6700 1550);
DISPLAY 0.680851 (-6700 1550);
PAINT MONO (-6700 1550);
DISPLAY INVISIBLE (-6700 1550);
FORCEPROP 2 LAST CDS_LOCATION C1M11
J 2
(-6700 1450);
DISPLAY 0.617021 (-6700 1450);
PAINT AQUA (-6700 1450);
DISPLAY INVISIBLE (-6700 1450);
FORCEPROP 1 LAST PATH I117
J 2
(-6700 1500);
DISPLAY 0.978723 (-6700 1500);
PAINT WHITE (-6700 1500);
DISPLAY INVISIBLE (-6700 1500);
FORCEPROP 2 LAST ROOM PCIE_STEERING
J 2
(-6650 1350);
PAINT MONO (-6650 1350);
DISPLAY INVISIBLE (-6650 1350);
FORCEPROP 1 LASTPIN (-6650 1250) $PN 2
J 2
(-6660 1230);
DISPLAY 0.787234 (-6660 1230);
PAINT ORANGE (-6660 1230);
DISPLAY INVISIBLE (-6660 1230);
FORCEPROP 1 LASTPIN (-6650 1450) $PN 1
J 2
(-6660 1430);
DISPLAY 0.787234 (-6660 1430);
PAINT ORANGE (-6660 1430);
DISPLAY INVISIBLE (-6660 1430);
FORCEADD TAP..7
(-6850 1100);
FORCEPROP 3 LASTPIN (-6850 1150) SIG_NAME P3E_OCP_CPU0_PE3_C_TXN<14>
J 0
(-6840 1160);
DISPLAY 0.659574 (-6840 1160);
PAINT MONO (-6840 1160);
DISPLAY INVISIBLE (-6840 1160);
FORCEPROP 1 LASTPIN (-6850 1150) BN 14
R 1
J 0
(-6857 1098);
DISPLAY 0.617021 (-6857 1098);
PAINT GREEN (-6857 1098);
FORCEPROP 2 LAST CDS_LIB mstr_standard
J 0
(-6850 1100);
PAINT ORANGE (-6850 1100);
DISPLAY INVISIBLE (-6850 1100);
FORCEPROP 1 LAST BODY_TYPE PLUMBING
J 0
(-6800 1100);
DISPLAY 2.276596 (-6800 1100);
PAINT GREEN (-6800 1100);
DISPLAY INVISIBLE (-6800 1100);
FORCEPROP 1 LAST HDL_TAP TRUE
J 0
(-6530 970);
DISPLAY 2.276596 (-6530 970);
PAINT GREEN (-6530 970);
DISPLAY INVISIBLE (-6530 970);
FORCEPROP 1 LAST PATH I118
J 0
(-6852 1100);
DISPLAY 0.872340 (-6852 1100);
PAINT GREEN (-6852 1100);
DISPLAY INVISIBLE (-6852 1100);
FORCEADD TAP..3
(-7050 1900);
FORCEPROP 3 LASTPIN (-7050 1850) SIG_NAME P3E_CPU0_PE3_OCP_TXN<15>
J 0
(-7040 1860);
DISPLAY 0.659574 (-7040 1860);
PAINT MONO (-7040 1860);
DISPLAY INVISIBLE (-7040 1860);
FORCEPROP 1 LASTPIN (-7050 1850) BN 15
R 1
J 0
(-7057 1838);
DISPLAY 0.617021 (-7057 1838);
PAINT GREEN (-7057 1838);
FORCEPROP 2 LAST CDS_LIB mstr_standard
J 0
(-7050 1900);
PAINT ORANGE (-7050 1900);
DISPLAY INVISIBLE (-7050 1900);
FORCEPROP 1 LAST BODY_TYPE PLUMBING
J 0
(-7000 1850);
DISPLAY 2.276596 (-7000 1850);
PAINT GREEN (-7000 1850);
DISPLAY INVISIBLE (-7000 1850);
FORCEPROP 1 LAST HDL_TAP TRUE
J 0
(-6730 1770);
DISPLAY 2.276596 (-6730 1770);
PAINT GREEN (-6730 1770);
DISPLAY INVISIBLE (-6730 1770);
FORCEPROP 1 LAST PATH I119
J 0
(-7052 1900);
DISPLAY 0.872340 (-7052 1900);
PAINT GREEN (-7052 1900);
DISPLAY INVISIBLE (-7052 1900);
FORCEADD OFFPAGE..1
(-7225 1950);
FORCEPROP 2 LAST $XR0 32 
J 0
(-7446 1950);
DISPLAY 0.638298 (-7446 1950);
PAINT MONO (-7446 1950);
FORCEPROP 2 LAST CDS_LIB mstr_standard
J 0
(-7225 1950);
PAINT ORANGE (-7225 1950);
DISPLAY INVISIBLE (-7225 1950);
FORCEPROP 1 LAST OFFPAGE TRUE
J 0
(-6905 1820);
PAINT GREEN (-6905 1820);
DISPLAY INVISIBLE (-6905 1820);
FORCEPROP 1 LAST COMMENT_BODY TRUE
J 0
(-7105 1850);
DISPLAY 2.276596 (-7105 1850);
PAINT GREEN (-7105 1850);
DISPLAY INVISIBLE (-7105 1850);
FORCEPROP 2 LAST PATH I120
J 0
(-7475 2000);
DISPLAY 1.021277 (-7475 2000);
PAINT ORANGE (-7475 2000);
DISPLAY INVISIBLE (-7475 2000);
FORCEADD TAP..7
(-7050 1100);
FORCEPROP 3 LASTPIN (-7050 1150) SIG_NAME P3E_OCP_CPU0_PE3_C_TXN<15>
J 0
(-7040 1160);
DISPLAY 0.659574 (-7040 1160);
PAINT MONO (-7040 1160);
DISPLAY INVISIBLE (-7040 1160);
FORCEPROP 1 LASTPIN (-7050 1150) BN 15
R 1
J 0
(-7057 1098);
DISPLAY 0.617021 (-7057 1098);
PAINT GREEN (-7057 1098);
FORCEPROP 2 LAST CDS_LIB mstr_standard
J 0
(-7050 1100);
PAINT ORANGE (-7050 1100);
DISPLAY INVISIBLE (-7050 1100);
FORCEPROP 1 LAST BODY_TYPE PLUMBING
J 0
(-7000 1100);
DISPLAY 2.276596 (-7000 1100);
PAINT GREEN (-7000 1100);
DISPLAY INVISIBLE (-7000 1100);
FORCEPROP 1 LAST HDL_TAP TRUE
J 0
(-6730 970);
DISPLAY 2.276596 (-6730 970);
PAINT GREEN (-6730 970);
DISPLAY INVISIBLE (-6730 970);
FORCEPROP 1 LAST PATH I121
J 0
(-7052 1100);
DISPLAY 0.872340 (-7052 1100);
PAINT GREEN (-7052 1100);
DISPLAY INVISIBLE (-7052 1100);
FORCEADD CAP..1
R 2
(-7050 1350);
FORCEPROP 1 LAST LOCATION C1M7
J 2
(-7100 1450);
DISPLAY 0.617021 (-7100 1450);
PAINT AQUA (-7100 1450);
FORCEPROP 1 LAST PART_NUMBER A36096-155
J 2
(-7100 1200);
DISPLAY 0.617021 (-7100 1200);
PAINT BLUE (-7100 1200);
FORCEPROP 1 LAST VALUE 0.22UF
J 2
(-7100 1400);
DISPLAY 0.617021 (-7100 1400);
PAINT SKYBLUE (-7100 1400);
FORCEPROP 1 LAST TOLERANCE 10%
J 2
(-7100 1300);
DISPLAY 0.617021 (-7100 1300);
PAINT SKYBLUE (-7100 1300);
FORCEPROP 1 LAST PACK_TYPE 0402
J 2
(-7100 1150);
DISPLAY 0.617021 (-7100 1150);
PAINT SKYBLUE (-7100 1150);
FORCEPROP 1 LAST VOLTAGE 16V
J 2
(-7100 1350);
DISPLAY 0.617021 (-7100 1350);
PAINT SKYBLUE (-7100 1350);
FORCEPROP 1 LAST MATERIAL X7R
J 2
(-7100 1250);
DISPLAY 0.617021 (-7100 1250);
PAINT SKYBLUE (-7100 1250);
FORCEPROP 2 LAST CDS_LIB mstr_discrete
J 0
(-7050 1350);
PAINT ORANGE (-7050 1350);
DISPLAY INVISIBLE (-7050 1350);
FORCEPROP 0 LAST CDS_SEC 1
J 0
(-7100 1500);
PAINT ORANGE (-7100 1500);
DISPLAY INVISIBLE (-7100 1500);
FORCEPROP 2 LAST $SEC 1
J 0
(-7100 1550);
DISPLAY 0.680851 (-7100 1550);
PAINT MONO (-7100 1550);
DISPLAY INVISIBLE (-7100 1550);
FORCEPROP 2 LAST CDS_LOCATION C1M7
J 2
(-7100 1450);
DISPLAY 0.617021 (-7100 1450);
PAINT AQUA (-7100 1450);
DISPLAY INVISIBLE (-7100 1450);
FORCEPROP 1 LAST PATH I122
J 2
(-7100 1500);
DISPLAY 0.978723 (-7100 1500);
PAINT WHITE (-7100 1500);
DISPLAY INVISIBLE (-7100 1500);
FORCEPROP 2 LAST ROOM PCIE_STEERING
J 2
(-7050 1350);
PAINT MONO (-7050 1350);
DISPLAY INVISIBLE (-7050 1350);
FORCEPROP 1 LASTPIN (-7050 1250) $PN 2
J 2
(-7060 1230);
DISPLAY 0.787234 (-7060 1230);
PAINT ORANGE (-7060 1230);
DISPLAY INVISIBLE (-7060 1230);
FORCEPROP 1 LASTPIN (-7050 1450) $PN 1
J 2
(-7060 1430);
DISPLAY 0.787234 (-7060 1430);
PAINT ORANGE (-7060 1430);
DISPLAY INVISIBLE (-7060 1430);
FORCEADD CAP..1
R 2
(-5275 1650);
FORCEPROP 1 LAST LOCATION C2R7
J 2
(-5325 1750);
DISPLAY 0.617021 (-5325 1750);
PAINT AQUA (-5325 1750);
FORCEPROP 1 LAST PART_NUMBER A36096-155
J 2
(-5325 1500);
DISPLAY 0.617021 (-5325 1500);
PAINT BLUE (-5325 1500);
FORCEPROP 1 LAST VALUE 0.22UF
J 2
(-5325 1700);
DISPLAY 0.617021 (-5325 1700);
PAINT SKYBLUE (-5325 1700);
FORCEPROP 1 LAST TOLERANCE 10%
J 2
(-5325 1600);
DISPLAY 0.617021 (-5325 1600);
PAINT SKYBLUE (-5325 1600);
FORCEPROP 1 LAST PACK_TYPE 0402
J 2
(-5325 1450);
DISPLAY 0.617021 (-5325 1450);
PAINT SKYBLUE (-5325 1450);
FORCEPROP 1 LAST VOLTAGE 16V
J 2
(-5325 1650);
DISPLAY 0.617021 (-5325 1650);
PAINT SKYBLUE (-5325 1650);
FORCEPROP 1 LAST MATERIAL X7R
J 2
(-5325 1550);
DISPLAY 0.617021 (-5325 1550);
PAINT SKYBLUE (-5325 1550);
FORCEPROP 2 LAST CDS_LIB mstr_discrete
J 0
(-5275 1650);
PAINT ORANGE (-5275 1650);
DISPLAY INVISIBLE (-5275 1650);
FORCEPROP 2 LAST BOM_COST IO_SLOT
J 0
(-5525 1800);
PAINT MONO (-5525 1800);
DISPLAY INVISIBLE (-5525 1800);
FORCEPROP 0 LAST CDS_SEC 1
J 0
(-5325 1800);
PAINT ORANGE (-5325 1800);
DISPLAY INVISIBLE (-5325 1800);
FORCEPROP 2 LAST $SEC 1
J 0
(-5325 1850);
DISPLAY 0.680851 (-5325 1850);
PAINT MONO (-5325 1850);
DISPLAY INVISIBLE (-5325 1850);
FORCEPROP 2 LAST CDS_LOCATION C2R7
J 2
(-5325 1750);
DISPLAY 0.617021 (-5325 1750);
PAINT AQUA (-5325 1750);
DISPLAY INVISIBLE (-5325 1750);
FORCEPROP 1 LAST PATH I123
J 2
(-5325 1800);
DISPLAY 0.978723 (-5325 1800);
PAINT WHITE (-5325 1800);
DISPLAY INVISIBLE (-5325 1800);
FORCEPROP 2 LAST ROOM PCIE_STEERING
J 2
(-5275 1650);
PAINT MONO (-5275 1650);
DISPLAY INVISIBLE (-5275 1650);
FORCEPROP 1 LASTPIN (-5275 1550) $PN 2
J 2
(-5285 1530);
DISPLAY 0.787234 (-5285 1530);
PAINT ORANGE (-5285 1530);
DISPLAY INVISIBLE (-5285 1530);
FORCEPROP 1 LASTPIN (-5275 1750) $PN 1
J 2
(-5285 1730);
DISPLAY 0.787234 (-5285 1730);
PAINT ORANGE (-5285 1730);
DISPLAY INVISIBLE (-5285 1730);
FORCEADD TAP..7
(-5300 2100);
FORCEPROP 3 LASTPIN (-5300 2150) SIG_NAME P3E_OCP_CPU0_PE3_C_TXP<6>
J 0
(-5290 2160);
DISPLAY 0.659574 (-5290 2160);
PAINT MONO (-5290 2160);
DISPLAY INVISIBLE (-5290 2160);
FORCEPROP 1 LASTPIN (-5300 2150) BN 6
R 1
J 0
(-5307 2098);
DISPLAY 0.617021 (-5307 2098);
PAINT GREEN (-5307 2098);
FORCEPROP 2 LAST CDS_LIB mstr_standard
J 0
(-5300 2100);
PAINT ORANGE (-5300 2100);
DISPLAY INVISIBLE (-5300 2100);
FORCEPROP 1 LAST BODY_TYPE PLUMBING
J 0
(-5250 2100);
DISPLAY 2.276596 (-5250 2100);
PAINT GREEN (-5250 2100);
DISPLAY INVISIBLE (-5250 2100);
FORCEPROP 1 LAST HDL_TAP TRUE
J 0
(-4980 1970);
DISPLAY 2.276596 (-4980 1970);
PAINT GREEN (-4980 1970);
DISPLAY INVISIBLE (-4980 1970);
FORCEPROP 1 LAST PATH I124
J 0
(-5302 2100);
DISPLAY 0.872340 (-5302 2100);
PAINT GREEN (-5302 2100);
DISPLAY INVISIBLE (-5302 2100);
FORCEADD TAP..3
(-5500 2900);
FORCEPROP 3 LASTPIN (-5500 2850) SIG_NAME P3E_CPU0_PE3_OCP_TXP<7>
J 0
(-5490 2860);
DISPLAY 0.659574 (-5490 2860);
PAINT MONO (-5490 2860);
DISPLAY INVISIBLE (-5490 2860);
FORCEPROP 1 LASTPIN (-5500 2850) BN 7
R 1
J 0
(-5507 2838);
DISPLAY 0.617021 (-5507 2838);
PAINT GREEN (-5507 2838);
FORCEPROP 2 LAST CDS_LIB mstr_standard
J 0
(-5500 2900);
PAINT ORANGE (-5500 2900);
DISPLAY INVISIBLE (-5500 2900);
FORCEPROP 1 LAST BODY_TYPE PLUMBING
J 0
(-5450 2850);
DISPLAY 2.276596 (-5450 2850);
PAINT GREEN (-5450 2850);
DISPLAY INVISIBLE (-5450 2850);
FORCEPROP 1 LAST HDL_TAP TRUE
J 0
(-5180 2770);
DISPLAY 2.276596 (-5180 2770);
PAINT GREEN (-5180 2770);
DISPLAY INVISIBLE (-5180 2770);
FORCEPROP 1 LAST PATH I125
J 0
(-5502 2900);
DISPLAY 0.872340 (-5502 2900);
PAINT GREEN (-5502 2900);
DISPLAY INVISIBLE (-5502 2900);
FORCEADD TAP..3
(-4900 2900);
FORCEPROP 3 LASTPIN (-4900 2850) SIG_NAME P3E_CPU0_PE3_OCP_TXP<4>
J 0
(-4890 2860);
DISPLAY 0.659574 (-4890 2860);
PAINT MONO (-4890 2860);
DISPLAY INVISIBLE (-4890 2860);
FORCEPROP 1 LASTPIN (-4900 2850) BN 4
R 1
J 0
(-4907 2838);
DISPLAY 0.617021 (-4907 2838);
PAINT GREEN (-4907 2838);
FORCEPROP 2 LAST CDS_LIB mstr_standard
J 0
(-4900 2900);
PAINT ORANGE (-4900 2900);
DISPLAY INVISIBLE (-4900 2900);
FORCEPROP 1 LAST BODY_TYPE PLUMBING
J 0
(-4850 2850);
DISPLAY 2.276596 (-4850 2850);
PAINT GREEN (-4850 2850);
DISPLAY INVISIBLE (-4850 2850);
FORCEPROP 1 LAST HDL_TAP TRUE
J 0
(-4580 2770);
DISPLAY 2.276596 (-4580 2770);
PAINT GREEN (-4580 2770);
DISPLAY INVISIBLE (-4580 2770);
FORCEPROP 1 LAST PATH I126
J 0
(-4902 2900);
DISPLAY 0.872340 (-4902 2900);
PAINT GREEN (-4902 2900);
DISPLAY INVISIBLE (-4902 2900);
FORCEADD TAP..3
(-5100 2900);
FORCEPROP 3 LASTPIN (-5100 2850) SIG_NAME P3E_CPU0_PE3_OCP_TXP<5>
J 0
(-5090 2860);
DISPLAY 0.659574 (-5090 2860);
PAINT MONO (-5090 2860);
DISPLAY INVISIBLE (-5090 2860);
FORCEPROP 1 LASTPIN (-5100 2850) BN 5
R 1
J 0
(-5107 2838);
DISPLAY 0.617021 (-5107 2838);
PAINT GREEN (-5107 2838);
FORCEPROP 2 LAST CDS_LIB mstr_standard
J 0
(-5100 2900);
PAINT ORANGE (-5100 2900);
DISPLAY INVISIBLE (-5100 2900);
FORCEPROP 1 LAST BODY_TYPE PLUMBING
J 0
(-5050 2850);
DISPLAY 2.276596 (-5050 2850);
PAINT GREEN (-5050 2850);
DISPLAY INVISIBLE (-5050 2850);
FORCEPROP 1 LAST HDL_TAP TRUE
J 0
(-4780 2770);
DISPLAY 2.276596 (-4780 2770);
PAINT GREEN (-4780 2770);
DISPLAY INVISIBLE (-4780 2770);
FORCEPROP 1 LAST PATH I127
J 0
(-5102 2900);
DISPLAY 0.872340 (-5102 2900);
PAINT GREEN (-5102 2900);
DISPLAY INVISIBLE (-5102 2900);
FORCEADD CAP..1
R 2
(-4900 2650);
FORCEPROP 1 LAST LOCATION C1R10
J 2
(-4950 2750);
DISPLAY 0.617021 (-4950 2750);
PAINT AQUA (-4950 2750);
FORCEPROP 1 LAST PART_NUMBER A36096-155
J 2
(-4950 2500);
DISPLAY 0.617021 (-4950 2500);
PAINT BLUE (-4950 2500);
FORCEPROP 1 LAST VALUE 0.22UF
J 2
(-4950 2700);
DISPLAY 0.617021 (-4950 2700);
PAINT SKYBLUE (-4950 2700);
FORCEPROP 1 LAST TOLERANCE 10%
J 2
(-4950 2600);
DISPLAY 0.617021 (-4950 2600);
PAINT SKYBLUE (-4950 2600);
FORCEPROP 1 LAST PACK_TYPE 0402
J 2
(-4950 2450);
DISPLAY 0.617021 (-4950 2450);
PAINT SKYBLUE (-4950 2450);
FORCEPROP 1 LAST VOLTAGE 16V
J 2
(-4950 2650);
DISPLAY 0.617021 (-4950 2650);
PAINT SKYBLUE (-4950 2650);
FORCEPROP 1 LAST MATERIAL X7R
J 2
(-4950 2550);
DISPLAY 0.617021 (-4950 2550);
PAINT SKYBLUE (-4950 2550);
FORCEPROP 2 LAST CDS_LIB mstr_discrete
J 0
(-4900 2650);
PAINT ORANGE (-4900 2650);
DISPLAY INVISIBLE (-4900 2650);
FORCEPROP 2 LAST BOM_COST IO_SLOT
J 0
(-5150 2800);
PAINT MONO (-5150 2800);
DISPLAY INVISIBLE (-5150 2800);
FORCEPROP 0 LAST CDS_SEC 1
J 0
(-4950 2800);
PAINT ORANGE (-4950 2800);
DISPLAY INVISIBLE (-4950 2800);
FORCEPROP 2 LAST $SEC 1
J 0
(-4950 2850);
DISPLAY 0.680851 (-4950 2850);
PAINT MONO (-4950 2850);
DISPLAY INVISIBLE (-4950 2850);
FORCEPROP 2 LAST CDS_LOCATION C1R10
J 2
(-4950 2750);
DISPLAY 0.617021 (-4950 2750);
PAINT AQUA (-4950 2750);
DISPLAY INVISIBLE (-4950 2750);
FORCEPROP 1 LAST PATH I128
J 2
(-4950 2800);
DISPLAY 0.978723 (-4950 2800);
PAINT WHITE (-4950 2800);
DISPLAY INVISIBLE (-4950 2800);
FORCEPROP 2 LAST ROOM PCIE_STEERING
J 2
(-4900 2650);
PAINT MONO (-4900 2650);
DISPLAY INVISIBLE (-4900 2650);
FORCEPROP 1 LASTPIN (-4900 2550) $PN 2
J 2
(-4910 2530);
DISPLAY 0.787234 (-4910 2530);
PAINT ORANGE (-4910 2530);
DISPLAY INVISIBLE (-4910 2530);
FORCEPROP 1 LASTPIN (-4900 2750) $PN 1
J 2
(-4910 2730);
DISPLAY 0.787234 (-4910 2730);
PAINT ORANGE (-4910 2730);
DISPLAY INVISIBLE (-4910 2730);
FORCEADD TAP..7
(-4900 2100);
FORCEPROP 3 LASTPIN (-4900 2150) SIG_NAME P3E_OCP_CPU0_PE3_C_TXP<4>
J 0
(-4890 2160);
DISPLAY 0.659574 (-4890 2160);
PAINT MONO (-4890 2160);
DISPLAY INVISIBLE (-4890 2160);
FORCEPROP 1 LASTPIN (-4900 2150) BN 4
R 1
J 0
(-4907 2098);
DISPLAY 0.617021 (-4907 2098);
PAINT GREEN (-4907 2098);
FORCEPROP 2 LAST CDS_LIB mstr_standard
J 0
(-4900 2100);
PAINT ORANGE (-4900 2100);
DISPLAY INVISIBLE (-4900 2100);
FORCEPROP 1 LAST BODY_TYPE PLUMBING
J 0
(-4850 2100);
DISPLAY 2.276596 (-4850 2100);
PAINT GREEN (-4850 2100);
DISPLAY INVISIBLE (-4850 2100);
FORCEPROP 1 LAST HDL_TAP TRUE
J 0
(-4580 1970);
DISPLAY 2.276596 (-4580 1970);
PAINT GREEN (-4580 1970);
DISPLAY INVISIBLE (-4580 1970);
FORCEPROP 1 LAST PATH I129
J 0
(-4902 2100);
DISPLAY 0.872340 (-4902 2100);
PAINT GREEN (-4902 2100);
DISPLAY INVISIBLE (-4902 2100);
FORCEADD CAP..1
R 2
(-5100 2350);
FORCEPROP 1 LAST LOCATION C2R14
J 2
(-5150 2450);
DISPLAY 0.617021 (-5150 2450);
PAINT AQUA (-5150 2450);
FORCEPROP 1 LAST PART_NUMBER A36096-155
J 2
(-5150 2200);
DISPLAY 0.617021 (-5150 2200);
PAINT BLUE (-5150 2200);
FORCEPROP 1 LAST VALUE 0.22UF
J 2
(-5150 2400);
DISPLAY 0.617021 (-5150 2400);
PAINT SKYBLUE (-5150 2400);
FORCEPROP 1 LAST TOLERANCE 10%
J 2
(-5150 2300);
DISPLAY 0.617021 (-5150 2300);
PAINT SKYBLUE (-5150 2300);
FORCEPROP 1 LAST PACK_TYPE 0402
J 2
(-5150 2150);
DISPLAY 0.617021 (-5150 2150);
PAINT SKYBLUE (-5150 2150);
FORCEPROP 1 LAST VOLTAGE 16V
J 2
(-5150 2350);
DISPLAY 0.617021 (-5150 2350);
PAINT SKYBLUE (-5150 2350);
FORCEPROP 1 LAST MATERIAL X7R
J 2
(-5150 2250);
DISPLAY 0.617021 (-5150 2250);
PAINT SKYBLUE (-5150 2250);
FORCEPROP 2 LAST CDS_LIB mstr_discrete
J 0
(-5100 2350);
PAINT ORANGE (-5100 2350);
DISPLAY INVISIBLE (-5100 2350);
FORCEPROP 2 LAST BOM_COST IO_SLOT
J 0
(-5350 2500);
PAINT MONO (-5350 2500);
DISPLAY INVISIBLE (-5350 2500);
FORCEPROP 0 LAST CDS_SEC 1
J 0
(-5150 2500);
PAINT ORANGE (-5150 2500);
DISPLAY INVISIBLE (-5150 2500);
FORCEPROP 2 LAST $SEC 1
J 0
(-5150 2550);
DISPLAY 0.680851 (-5150 2550);
PAINT MONO (-5150 2550);
DISPLAY INVISIBLE (-5150 2550);
FORCEPROP 1 LAST PATH I130
J 2
(-5150 2500);
DISPLAY 0.978723 (-5150 2500);
PAINT WHITE (-5150 2500);
DISPLAY INVISIBLE (-5150 2500);
FORCEPROP 2 LAST ROOM PCIE_STEERING
J 2
(-5100 2350);
PAINT MONO (-5100 2350);
DISPLAY INVISIBLE (-5100 2350);
FORCEPROP 1 LASTPIN (-5100 2250) $PN 2
J 2
(-5110 2230);
DISPLAY 0.787234 (-5110 2230);
PAINT ORANGE (-5110 2230);
DISPLAY INVISIBLE (-5110 2230);
FORCEPROP 1 LASTPIN (-5100 2450) $PN 1
J 2
(-5110 2430);
DISPLAY 0.787234 (-5110 2430);
PAINT ORANGE (-5110 2430);
DISPLAY INVISIBLE (-5110 2430);
FORCEADD TAP..7
(-5100 2100);
FORCEPROP 3 LASTPIN (-5100 2150) SIG_NAME P3E_OCP_CPU0_PE3_C_TXP<5>
J 0
(-5090 2160);
DISPLAY 0.659574 (-5090 2160);
PAINT MONO (-5090 2160);
DISPLAY INVISIBLE (-5090 2160);
FORCEPROP 1 LASTPIN (-5100 2150) BN 5
R 1
J 0
(-5107 2098);
DISPLAY 0.617021 (-5107 2098);
PAINT GREEN (-5107 2098);
FORCEPROP 2 LAST CDS_LIB mstr_standard
J 0
(-5100 2100);
PAINT ORANGE (-5100 2100);
DISPLAY INVISIBLE (-5100 2100);
FORCEPROP 1 LAST BODY_TYPE PLUMBING
J 0
(-5050 2100);
DISPLAY 2.276596 (-5050 2100);
PAINT GREEN (-5050 2100);
DISPLAY INVISIBLE (-5050 2100);
FORCEPROP 1 LAST HDL_TAP TRUE
J 0
(-4780 1970);
DISPLAY 2.276596 (-4780 1970);
PAINT GREEN (-4780 1970);
DISPLAY INVISIBLE (-4780 1970);
FORCEPROP 1 LAST PATH I131
J 0
(-5102 2100);
DISPLAY 0.872340 (-5102 2100);
PAINT GREEN (-5102 2100);
DISPLAY INVISIBLE (-5102 2100);
FORCEADD TAP..3
(-4875 1900);
FORCEPROP 3 LASTPIN (-4875 1850) SIG_NAME P3E_CPU0_PE3_OCP_TXN<4>
J 0
(-4865 1860);
DISPLAY 0.659574 (-4865 1860);
PAINT MONO (-4865 1860);
DISPLAY INVISIBLE (-4865 1860);
FORCEPROP 1 LASTPIN (-4875 1850) BN 4
R 1
J 0
(-4882 1838);
DISPLAY 0.617021 (-4882 1838);
PAINT GREEN (-4882 1838);
FORCEPROP 2 LAST CDS_LIB mstr_standard
J 0
(-4875 1900);
PAINT ORANGE (-4875 1900);
DISPLAY INVISIBLE (-4875 1900);
FORCEPROP 1 LAST BODY_TYPE PLUMBING
J 0
(-4825 1850);
DISPLAY 2.276596 (-4825 1850);
PAINT GREEN (-4825 1850);
DISPLAY INVISIBLE (-4825 1850);
FORCEPROP 1 LAST HDL_TAP TRUE
J 0
(-4555 1770);
DISPLAY 2.276596 (-4555 1770);
PAINT GREEN (-4555 1770);
DISPLAY INVISIBLE (-4555 1770);
FORCEPROP 1 LAST PATH I133
J 0
(-4877 1900);
DISPLAY 0.872340 (-4877 1900);
PAINT GREEN (-4877 1900);
DISPLAY INVISIBLE (-4877 1900);
FORCEADD CAP..1
R 2
(-4875 1650);
FORCEPROP 1 LAST LOCATION C1R9
J 2
(-4925 1750);
DISPLAY 0.617021 (-4925 1750);
PAINT AQUA (-4925 1750);
FORCEPROP 1 LAST PART_NUMBER A36096-155
J 2
(-4925 1500);
DISPLAY 0.617021 (-4925 1500);
PAINT BLUE (-4925 1500);
FORCEPROP 1 LAST VALUE 0.22UF
J 2
(-4925 1700);
DISPLAY 0.617021 (-4925 1700);
PAINT SKYBLUE (-4925 1700);
FORCEPROP 1 LAST TOLERANCE 10%
J 2
(-4925 1600);
DISPLAY 0.617021 (-4925 1600);
PAINT SKYBLUE (-4925 1600);
FORCEPROP 1 LAST PACK_TYPE 0402
J 2
(-4925 1450);
DISPLAY 0.617021 (-4925 1450);
PAINT SKYBLUE (-4925 1450);
FORCEPROP 1 LAST VOLTAGE 16V
J 2
(-4925 1650);
DISPLAY 0.617021 (-4925 1650);
PAINT SKYBLUE (-4925 1650);
FORCEPROP 1 LAST MATERIAL X7R
J 2
(-4925 1550);
DISPLAY 0.617021 (-4925 1550);
PAINT SKYBLUE (-4925 1550);
FORCEPROP 2 LAST CDS_LIB mstr_discrete
J 0
(-4875 1650);
PAINT ORANGE (-4875 1650);
DISPLAY INVISIBLE (-4875 1650);
FORCEPROP 2 LAST BOM_COST IO_SLOT
J 0
(-5125 1800);
PAINT MONO (-5125 1800);
DISPLAY INVISIBLE (-5125 1800);
FORCEPROP 0 LAST CDS_SEC 1
J 0
(-4925 1800);
PAINT ORANGE (-4925 1800);
DISPLAY INVISIBLE (-4925 1800);
FORCEPROP 2 LAST $SEC 1
J 0
(-4925 1850);
DISPLAY 0.680851 (-4925 1850);
PAINT MONO (-4925 1850);
DISPLAY INVISIBLE (-4925 1850);
FORCEPROP 2 LAST CDS_LOCATION C1R9
J 2
(-4925 1750);
DISPLAY 0.617021 (-4925 1750);
PAINT AQUA (-4925 1750);
DISPLAY INVISIBLE (-4925 1750);
FORCEPROP 1 LAST PATH I134
J 2
(-4925 1800);
DISPLAY 0.978723 (-4925 1800);
PAINT WHITE (-4925 1800);
DISPLAY INVISIBLE (-4925 1800);
FORCEPROP 2 LAST ROOM PCIE_STEERING
J 2
(-4875 1650);
PAINT MONO (-4875 1650);
DISPLAY INVISIBLE (-4875 1650);
FORCEPROP 1 LASTPIN (-4875 1550) $PN 2
J 2
(-4885 1530);
DISPLAY 0.787234 (-4885 1530);
PAINT ORANGE (-4885 1530);
DISPLAY INVISIBLE (-4885 1530);
FORCEPROP 1 LASTPIN (-4875 1750) $PN 1
J 2
(-4885 1730);
DISPLAY 0.787234 (-4885 1730);
PAINT ORANGE (-4885 1730);
DISPLAY INVISIBLE (-4885 1730);
FORCEADD TAP..3
(-5075 1900);
FORCEPROP 3 LASTPIN (-5075 1850) SIG_NAME P3E_CPU0_PE3_OCP_TXN<5>
J 0
(-5065 1860);
DISPLAY 0.659574 (-5065 1860);
PAINT MONO (-5065 1860);
DISPLAY INVISIBLE (-5065 1860);
FORCEPROP 1 LASTPIN (-5075 1850) BN 5
R 1
J 0
(-5082 1838);
DISPLAY 0.617021 (-5082 1838);
PAINT GREEN (-5082 1838);
FORCEPROP 2 LAST CDS_LIB mstr_standard
J 0
(-5075 1900);
PAINT ORANGE (-5075 1900);
DISPLAY INVISIBLE (-5075 1900);
FORCEPROP 1 LAST BODY_TYPE PLUMBING
J 0
(-5025 1850);
DISPLAY 2.276596 (-5025 1850);
PAINT GREEN (-5025 1850);
DISPLAY INVISIBLE (-5025 1850);
FORCEPROP 1 LAST HDL_TAP TRUE
J 0
(-4755 1770);
DISPLAY 2.276596 (-4755 1770);
PAINT GREEN (-4755 1770);
DISPLAY INVISIBLE (-4755 1770);
FORCEPROP 1 LAST PATH I135
J 0
(-5077 1900);
DISPLAY 0.872340 (-5077 1900);
PAINT GREEN (-5077 1900);
DISPLAY INVISIBLE (-5077 1900);
FORCEADD TAP..7
(-4875 1100);
FORCEPROP 3 LASTPIN (-4875 1150) SIG_NAME P3E_OCP_CPU0_PE3_C_TXN<4>
J 0
(-4865 1160);
DISPLAY 0.659574 (-4865 1160);
PAINT MONO (-4865 1160);
DISPLAY INVISIBLE (-4865 1160);
FORCEPROP 1 LASTPIN (-4875 1150) BN 4
R 1
J 0
(-4882 1098);
DISPLAY 0.617021 (-4882 1098);
PAINT GREEN (-4882 1098);
FORCEPROP 2 LAST CDS_LIB mstr_standard
J 0
(-4875 1100);
PAINT ORANGE (-4875 1100);
DISPLAY INVISIBLE (-4875 1100);
FORCEPROP 1 LAST BODY_TYPE PLUMBING
J 0
(-4825 1100);
DISPLAY 2.276596 (-4825 1100);
PAINT GREEN (-4825 1100);
DISPLAY INVISIBLE (-4825 1100);
FORCEPROP 1 LAST HDL_TAP TRUE
J 0
(-4555 970);
DISPLAY 2.276596 (-4555 970);
PAINT GREEN (-4555 970);
DISPLAY INVISIBLE (-4555 970);
FORCEPROP 1 LAST PATH I136
J 0
(-4877 1100);
DISPLAY 0.872340 (-4877 1100);
PAINT GREEN (-4877 1100);
DISPLAY INVISIBLE (-4877 1100);
FORCEADD CAP..1
R 2
(-5075 1350);
FORCEPROP 1 LAST LOCATION C2R13
J 2
(-5125 1450);
DISPLAY 0.617021 (-5125 1450);
PAINT AQUA (-5125 1450);
FORCEPROP 1 LAST PART_NUMBER A36096-155
J 2
(-5125 1200);
DISPLAY 0.617021 (-5125 1200);
PAINT BLUE (-5125 1200);
FORCEPROP 1 LAST VALUE 0.22UF
J 2
(-5125 1400);
DISPLAY 0.617021 (-5125 1400);
PAINT SKYBLUE (-5125 1400);
FORCEPROP 1 LAST TOLERANCE 10%
J 2
(-5125 1300);
DISPLAY 0.617021 (-5125 1300);
PAINT SKYBLUE (-5125 1300);
FORCEPROP 1 LAST PACK_TYPE 0402
J 2
(-5125 1150);
DISPLAY 0.617021 (-5125 1150);
PAINT SKYBLUE (-5125 1150);
FORCEPROP 1 LAST VOLTAGE 16V
J 2
(-5125 1350);
DISPLAY 0.617021 (-5125 1350);
PAINT SKYBLUE (-5125 1350);
FORCEPROP 1 LAST MATERIAL X7R
J 2
(-5125 1250);
DISPLAY 0.617021 (-5125 1250);
PAINT SKYBLUE (-5125 1250);
FORCEPROP 2 LAST CDS_LIB mstr_discrete
J 0
(-5075 1350);
PAINT ORANGE (-5075 1350);
DISPLAY INVISIBLE (-5075 1350);
FORCEPROP 2 LAST BOM_COST IO_SLOT
J 0
(-5325 1500);
PAINT MONO (-5325 1500);
DISPLAY INVISIBLE (-5325 1500);
FORCEPROP 0 LAST CDS_SEC 1
J 0
(-5125 1500);
PAINT ORANGE (-5125 1500);
DISPLAY INVISIBLE (-5125 1500);
FORCEPROP 2 LAST $SEC 1
J 0
(-5125 1550);
DISPLAY 0.680851 (-5125 1550);
PAINT MONO (-5125 1550);
DISPLAY INVISIBLE (-5125 1550);
FORCEPROP 1 LAST PATH I137
J 2
(-5125 1500);
DISPLAY 0.978723 (-5125 1500);
PAINT WHITE (-5125 1500);
DISPLAY INVISIBLE (-5125 1500);
FORCEPROP 2 LAST ROOM PCIE_STEERING
J 2
(-5075 1350);
PAINT MONO (-5075 1350);
DISPLAY INVISIBLE (-5075 1350);
FORCEPROP 1 LASTPIN (-5075 1250) $PN 2
J 2
(-5085 1230);
DISPLAY 0.787234 (-5085 1230);
PAINT ORANGE (-5085 1230);
DISPLAY INVISIBLE (-5085 1230);
FORCEPROP 1 LASTPIN (-5075 1450) $PN 1
J 2
(-5085 1430);
DISPLAY 0.787234 (-5085 1430);
PAINT ORANGE (-5085 1430);
DISPLAY INVISIBLE (-5085 1430);
FORCEADD TAP..7
(-5075 1100);
FORCEPROP 3 LASTPIN (-5075 1150) SIG_NAME P3E_OCP_CPU0_PE3_C_TXN<5>
J 0
(-5065 1160);
DISPLAY 0.659574 (-5065 1160);
PAINT MONO (-5065 1160);
DISPLAY INVISIBLE (-5065 1160);
FORCEPROP 1 LASTPIN (-5075 1150) BN 5
R 1
J 0
(-5082 1098);
DISPLAY 0.617021 (-5082 1098);
PAINT GREEN (-5082 1098);
FORCEPROP 2 LAST CDS_LIB mstr_standard
J 0
(-5075 1100);
PAINT ORANGE (-5075 1100);
DISPLAY INVISIBLE (-5075 1100);
FORCEPROP 1 LAST BODY_TYPE PLUMBING
J 0
(-5025 1100);
DISPLAY 2.276596 (-5025 1100);
PAINT GREEN (-5025 1100);
DISPLAY INVISIBLE (-5025 1100);
FORCEPROP 1 LAST HDL_TAP TRUE
J 0
(-4755 970);
DISPLAY 2.276596 (-4755 970);
PAINT GREEN (-4755 970);
DISPLAY INVISIBLE (-4755 970);
FORCEPROP 1 LAST PATH I138
J 0
(-5077 1100);
DISPLAY 0.872340 (-5077 1100);
PAINT GREEN (-5077 1100);
DISPLAY INVISIBLE (-5077 1100);
FORCEADD TAP..3
(-5300 2900);
FORCEPROP 3 LASTPIN (-5300 2850) SIG_NAME P3E_CPU0_PE3_OCP_TXP<6>
J 0
(-5290 2860);
DISPLAY 0.659574 (-5290 2860);
PAINT MONO (-5290 2860);
DISPLAY INVISIBLE (-5290 2860);
FORCEPROP 1 LASTPIN (-5300 2850) BN 6
R 1
J 0
(-5307 2838);
DISPLAY 0.617021 (-5307 2838);
PAINT GREEN (-5307 2838);
FORCEPROP 2 LAST CDS_LIB mstr_standard
J 0
(-5300 2900);
PAINT ORANGE (-5300 2900);
DISPLAY INVISIBLE (-5300 2900);
FORCEPROP 1 LAST BODY_TYPE PLUMBING
J 0
(-5250 2850);
DISPLAY 2.276596 (-5250 2850);
PAINT GREEN (-5250 2850);
DISPLAY INVISIBLE (-5250 2850);
FORCEPROP 1 LAST HDL_TAP TRUE
J 0
(-4980 2770);
DISPLAY 2.276596 (-4980 2770);
PAINT GREEN (-4980 2770);
DISPLAY INVISIBLE (-4980 2770);
FORCEPROP 1 LAST PATH I140
J 0
(-5302 2900);
DISPLAY 0.872340 (-5302 2900);
PAINT GREEN (-5302 2900);
DISPLAY INVISIBLE (-5302 2900);
FORCEADD CAP..1
R 2
(-5300 2650);
FORCEPROP 1 LAST LOCATION C2R8
J 2
(-5350 2750);
DISPLAY 0.617021 (-5350 2750);
PAINT AQUA (-5350 2750);
FORCEPROP 1 LAST PART_NUMBER A36096-155
J 2
(-5350 2500);
DISPLAY 0.617021 (-5350 2500);
PAINT BLUE (-5350 2500);
FORCEPROP 1 LAST VALUE 0.22UF
J 2
(-5350 2700);
DISPLAY 0.617021 (-5350 2700);
PAINT SKYBLUE (-5350 2700);
FORCEPROP 1 LAST TOLERANCE 10%
J 2
(-5350 2600);
DISPLAY 0.617021 (-5350 2600);
PAINT SKYBLUE (-5350 2600);
FORCEPROP 1 LAST PACK_TYPE 0402
J 2
(-5350 2450);
DISPLAY 0.617021 (-5350 2450);
PAINT SKYBLUE (-5350 2450);
FORCEPROP 1 LAST VOLTAGE 16V
J 2
(-5350 2650);
DISPLAY 0.617021 (-5350 2650);
PAINT SKYBLUE (-5350 2650);
FORCEPROP 1 LAST MATERIAL X7R
J 2
(-5350 2550);
DISPLAY 0.617021 (-5350 2550);
PAINT SKYBLUE (-5350 2550);
FORCEPROP 2 LAST CDS_LIB mstr_discrete
J 0
(-5300 2650);
PAINT ORANGE (-5300 2650);
DISPLAY INVISIBLE (-5300 2650);
FORCEPROP 2 LAST BOM_COST IO_SLOT
J 0
(-5550 2800);
PAINT MONO (-5550 2800);
DISPLAY INVISIBLE (-5550 2800);
FORCEPROP 0 LAST CDS_SEC 1
J 0
(-5350 2800);
PAINT ORANGE (-5350 2800);
DISPLAY INVISIBLE (-5350 2800);
FORCEPROP 2 LAST $SEC 1
J 0
(-5350 2850);
DISPLAY 0.680851 (-5350 2850);
PAINT MONO (-5350 2850);
DISPLAY INVISIBLE (-5350 2850);
FORCEPROP 2 LAST CDS_LOCATION C2R8
J 2
(-5350 2750);
DISPLAY 0.617021 (-5350 2750);
PAINT AQUA (-5350 2750);
DISPLAY INVISIBLE (-5350 2750);
FORCEPROP 1 LAST PATH I141
J 2
(-5350 2800);
DISPLAY 0.978723 (-5350 2800);
PAINT WHITE (-5350 2800);
DISPLAY INVISIBLE (-5350 2800);
FORCEPROP 2 LAST ROOM PCIE_STEERING
J 2
(-5300 2650);
PAINT MONO (-5300 2650);
DISPLAY INVISIBLE (-5300 2650);
FORCEPROP 1 LASTPIN (-5300 2550) $PN 2
J 2
(-5310 2530);
DISPLAY 0.787234 (-5310 2530);
PAINT ORANGE (-5310 2530);
DISPLAY INVISIBLE (-5310 2530);
FORCEPROP 1 LASTPIN (-5300 2750) $PN 1
J 2
(-5310 2730);
DISPLAY 0.787234 (-5310 2730);
PAINT ORANGE (-5310 2730);
DISPLAY INVISIBLE (-5310 2730);
FORCEADD CAP..1
R 2
(-5500 2350);
FORCEPROP 1 LAST LOCATION C2R10
J 2
(-5550 2450);
DISPLAY 0.617021 (-5550 2450);
PAINT AQUA (-5550 2450);
FORCEPROP 1 LAST PART_NUMBER A36096-155
J 2
(-5550 2200);
DISPLAY 0.617021 (-5550 2200);
PAINT BLUE (-5550 2200);
FORCEPROP 1 LAST VALUE 0.22UF
J 2
(-5550 2400);
DISPLAY 0.617021 (-5550 2400);
PAINT SKYBLUE (-5550 2400);
FORCEPROP 1 LAST TOLERANCE 10%
J 2
(-5550 2300);
DISPLAY 0.617021 (-5550 2300);
PAINT SKYBLUE (-5550 2300);
FORCEPROP 1 LAST PACK_TYPE 0402
J 2
(-5550 2150);
DISPLAY 0.617021 (-5550 2150);
PAINT SKYBLUE (-5550 2150);
FORCEPROP 1 LAST VOLTAGE 16V
J 2
(-5550 2350);
DISPLAY 0.617021 (-5550 2350);
PAINT SKYBLUE (-5550 2350);
FORCEPROP 1 LAST MATERIAL X7R
J 2
(-5550 2250);
DISPLAY 0.617021 (-5550 2250);
PAINT SKYBLUE (-5550 2250);
FORCEPROP 2 LAST CDS_LIB mstr_discrete
J 0
(-5500 2350);
PAINT ORANGE (-5500 2350);
DISPLAY INVISIBLE (-5500 2350);
FORCEPROP 2 LAST BOM_COST IO_SLOT
J 0
(-5750 2500);
PAINT MONO (-5750 2500);
DISPLAY INVISIBLE (-5750 2500);
FORCEPROP 0 LAST CDS_SEC 1
J 0
(-5550 2500);
PAINT ORANGE (-5550 2500);
DISPLAY INVISIBLE (-5550 2500);
FORCEPROP 2 LAST $SEC 1
J 0
(-5550 2550);
DISPLAY 0.680851 (-5550 2550);
PAINT MONO (-5550 2550);
DISPLAY INVISIBLE (-5550 2550);
FORCEPROP 2 LAST CDS_LOCATION C2R10
J 2
(-5550 2450);
DISPLAY 0.617021 (-5550 2450);
PAINT AQUA (-5550 2450);
DISPLAY INVISIBLE (-5550 2450);
FORCEPROP 1 LAST PATH I142
J 2
(-5550 2500);
DISPLAY 0.978723 (-5550 2500);
PAINT WHITE (-5550 2500);
DISPLAY INVISIBLE (-5550 2500);
FORCEPROP 2 LAST ROOM PCIE_STEERING
J 2
(-5500 2350);
PAINT MONO (-5500 2350);
DISPLAY INVISIBLE (-5500 2350);
FORCEPROP 1 LASTPIN (-5500 2250) $PN 2
J 2
(-5510 2230);
DISPLAY 0.787234 (-5510 2230);
PAINT ORANGE (-5510 2230);
DISPLAY INVISIBLE (-5510 2230);
FORCEPROP 1 LASTPIN (-5500 2450) $PN 1
J 2
(-5510 2430);
DISPLAY 0.787234 (-5510 2430);
PAINT ORANGE (-5510 2430);
DISPLAY INVISIBLE (-5510 2430);
FORCEADD TAP..7
(-5500 2100);
FORCEPROP 3 LASTPIN (-5500 2150) SIG_NAME P3E_OCP_CPU0_PE3_C_TXP<7>
J 0
(-5490 2160);
DISPLAY 0.659574 (-5490 2160);
PAINT MONO (-5490 2160);
DISPLAY INVISIBLE (-5490 2160);
FORCEPROP 1 LASTPIN (-5500 2150) BN 7
R 1
J 0
(-5507 2098);
DISPLAY 0.617021 (-5507 2098);
PAINT GREEN (-5507 2098);
FORCEPROP 2 LAST CDS_LIB mstr_standard
J 0
(-5500 2100);
PAINT ORANGE (-5500 2100);
DISPLAY INVISIBLE (-5500 2100);
FORCEPROP 1 LAST BODY_TYPE PLUMBING
J 0
(-5450 2100);
DISPLAY 2.276596 (-5450 2100);
PAINT GREEN (-5450 2100);
DISPLAY INVISIBLE (-5450 2100);
FORCEPROP 1 LAST HDL_TAP TRUE
J 0
(-5180 1970);
DISPLAY 2.276596 (-5180 1970);
PAINT GREEN (-5180 1970);
DISPLAY INVISIBLE (-5180 1970);
FORCEPROP 1 LAST PATH I143
J 0
(-5502 2100);
DISPLAY 0.872340 (-5502 2100);
PAINT GREEN (-5502 2100);
DISPLAY INVISIBLE (-5502 2100);
FORCEADD TAP..3
(-5275 1900);
FORCEPROP 3 LASTPIN (-5275 1850) SIG_NAME P3E_CPU0_PE3_OCP_TXN<6>
J 0
(-5265 1860);
DISPLAY 0.659574 (-5265 1860);
PAINT MONO (-5265 1860);
DISPLAY INVISIBLE (-5265 1860);
FORCEPROP 1 LASTPIN (-5275 1850) BN 6
R 1
J 0
(-5282 1838);
DISPLAY 0.617021 (-5282 1838);
PAINT GREEN (-5282 1838);
FORCEPROP 2 LAST CDS_LIB mstr_standard
J 0
(-5275 1900);
PAINT ORANGE (-5275 1900);
DISPLAY INVISIBLE (-5275 1900);
FORCEPROP 1 LAST BODY_TYPE PLUMBING
J 0
(-5225 1850);
DISPLAY 2.276596 (-5225 1850);
PAINT GREEN (-5225 1850);
DISPLAY INVISIBLE (-5225 1850);
FORCEPROP 1 LAST HDL_TAP TRUE
J 0
(-4955 1770);
DISPLAY 1.829787 (-4955 1770);
PAINT GREEN (-4955 1770);
DISPLAY INVISIBLE (-4955 1770);
FORCEPROP 1 LAST PATH I144
J 0
(-5277 1900);
DISPLAY 0.872340 (-5277 1900);
PAINT GREEN (-5277 1900);
DISPLAY INVISIBLE (-5277 1900);
FORCEADD TAP..3
(-5475 1900);
FORCEPROP 3 LASTPIN (-5475 1850) SIG_NAME P3E_CPU0_PE3_OCP_TXN<7>
J 0
(-5465 1860);
DISPLAY 0.659574 (-5465 1860);
PAINT MONO (-5465 1860);
DISPLAY INVISIBLE (-5465 1860);
FORCEPROP 1 LASTPIN (-5475 1850) BN 7
R 1
J 0
(-5482 1838);
DISPLAY 0.617021 (-5482 1838);
PAINT GREEN (-5482 1838);
FORCEPROP 2 LAST CDS_LIB mstr_standard
J 0
(-5475 1900);
PAINT ORANGE (-5475 1900);
DISPLAY INVISIBLE (-5475 1900);
FORCEPROP 1 LAST BODY_TYPE PLUMBING
J 0
(-5425 1850);
DISPLAY 2.276596 (-5425 1850);
PAINT GREEN (-5425 1850);
DISPLAY INVISIBLE (-5425 1850);
FORCEPROP 1 LAST HDL_TAP TRUE
J 0
(-5155 1770);
DISPLAY 2.276596 (-5155 1770);
PAINT GREEN (-5155 1770);
DISPLAY INVISIBLE (-5155 1770);
FORCEPROP 1 LAST PATH I145
J 0
(-5477 1900);
DISPLAY 0.872340 (-5477 1900);
PAINT GREEN (-5477 1900);
DISPLAY INVISIBLE (-5477 1900);
FORCEADD TAP..7
(-5275 1100);
FORCEPROP 3 LASTPIN (-5275 1150) SIG_NAME P3E_OCP_CPU0_PE3_C_TXN<6>
J 0
(-5265 1160);
DISPLAY 0.659574 (-5265 1160);
PAINT MONO (-5265 1160);
DISPLAY INVISIBLE (-5265 1160);
FORCEPROP 1 LASTPIN (-5275 1150) BN 6
R 1
J 0
(-5282 1098);
DISPLAY 0.617021 (-5282 1098);
PAINT GREEN (-5282 1098);
FORCEPROP 2 LAST CDS_LIB mstr_standard
J 0
(-5275 1100);
PAINT ORANGE (-5275 1100);
DISPLAY INVISIBLE (-5275 1100);
FORCEPROP 1 LAST BODY_TYPE PLUMBING
J 0
(-5225 1100);
DISPLAY 2.276596 (-5225 1100);
PAINT GREEN (-5225 1100);
DISPLAY INVISIBLE (-5225 1100);
FORCEPROP 1 LAST HDL_TAP TRUE
J 0
(-4955 970);
DISPLAY 2.276596 (-4955 970);
PAINT GREEN (-4955 970);
DISPLAY INVISIBLE (-4955 970);
FORCEPROP 1 LAST PATH I146
J 0
(-5277 1100);
DISPLAY 0.872340 (-5277 1100);
PAINT GREEN (-5277 1100);
DISPLAY INVISIBLE (-5277 1100);
FORCEADD CAP..1
R 2
(-5475 1350);
FORCEPROP 1 LAST LOCATION C2R9
J 2
(-5525 1450);
DISPLAY 0.617021 (-5525 1450);
PAINT AQUA (-5525 1450);
FORCEPROP 1 LAST PART_NUMBER A36096-155
J 2
(-5525 1200);
DISPLAY 0.617021 (-5525 1200);
PAINT BLUE (-5525 1200);
FORCEPROP 1 LAST VALUE 0.22UF
J 2
(-5525 1400);
DISPLAY 0.617021 (-5525 1400);
PAINT SKYBLUE (-5525 1400);
FORCEPROP 1 LAST TOLERANCE 10%
J 2
(-5525 1300);
DISPLAY 0.617021 (-5525 1300);
PAINT SKYBLUE (-5525 1300);
FORCEPROP 1 LAST PACK_TYPE 0402
J 2
(-5525 1150);
DISPLAY 0.617021 (-5525 1150);
PAINT SKYBLUE (-5525 1150);
FORCEPROP 1 LAST VOLTAGE 16V
J 2
(-5525 1350);
DISPLAY 0.617021 (-5525 1350);
PAINT SKYBLUE (-5525 1350);
FORCEPROP 1 LAST MATERIAL X7R
J 2
(-5525 1250);
DISPLAY 0.617021 (-5525 1250);
PAINT SKYBLUE (-5525 1250);
FORCEPROP 2 LAST CDS_LIB mstr_discrete
J 0
(-5475 1350);
PAINT ORANGE (-5475 1350);
DISPLAY INVISIBLE (-5475 1350);
FORCEPROP 2 LAST BOM_COST IO_SLOT
J 0
(-5725 1500);
PAINT MONO (-5725 1500);
DISPLAY INVISIBLE (-5725 1500);
FORCEPROP 0 LAST CDS_SEC 1
J 0
(-5525 1500);
PAINT ORANGE (-5525 1500);
DISPLAY INVISIBLE (-5525 1500);
FORCEPROP 2 LAST $SEC 1
J 0
(-5525 1550);
DISPLAY 0.680851 (-5525 1550);
PAINT MONO (-5525 1550);
DISPLAY INVISIBLE (-5525 1550);
FORCEPROP 2 LAST CDS_LOCATION C2R9
J 2
(-5525 1450);
DISPLAY 0.617021 (-5525 1450);
PAINT AQUA (-5525 1450);
DISPLAY INVISIBLE (-5525 1450);
FORCEPROP 1 LAST PATH I147
J 2
(-5525 1500);
DISPLAY 0.978723 (-5525 1500);
PAINT WHITE (-5525 1500);
DISPLAY INVISIBLE (-5525 1500);
FORCEPROP 2 LAST ROOM PCIE_STEERING
J 2
(-5475 1350);
PAINT MONO (-5475 1350);
DISPLAY INVISIBLE (-5475 1350);
FORCEPROP 1 LASTPIN (-5475 1250) $PN 2
J 2
(-5485 1230);
DISPLAY 0.787234 (-5485 1230);
PAINT ORANGE (-5485 1230);
DISPLAY INVISIBLE (-5485 1230);
FORCEPROP 1 LASTPIN (-5475 1450) $PN 1
J 2
(-5485 1430);
DISPLAY 0.787234 (-5485 1430);
PAINT ORANGE (-5485 1430);
DISPLAY INVISIBLE (-5485 1430);
FORCEADD TAP..7
(-5475 1100);
FORCEPROP 3 LASTPIN (-5475 1150) SIG_NAME P3E_OCP_CPU0_PE3_C_TXN<7>
J 0
(-5465 1160);
DISPLAY 0.659574 (-5465 1160);
PAINT MONO (-5465 1160);
DISPLAY INVISIBLE (-5465 1160);
FORCEPROP 1 LASTPIN (-5475 1150) BN 7
R 1
J 0
(-5482 1098);
DISPLAY 0.617021 (-5482 1098);
PAINT GREEN (-5482 1098);
FORCEPROP 2 LAST CDS_LIB mstr_standard
J 0
(-5475 1100);
PAINT ORANGE (-5475 1100);
DISPLAY INVISIBLE (-5475 1100);
FORCEPROP 1 LAST BODY_TYPE PLUMBING
J 0
(-5425 1100);
DISPLAY 2.276596 (-5425 1100);
PAINT GREEN (-5425 1100);
DISPLAY INVISIBLE (-5425 1100);
FORCEPROP 1 LAST HDL_TAP TRUE
J 0
(-5155 970);
DISPLAY 2.276596 (-5155 970);
PAINT GREEN (-5155 970);
DISPLAY INVISIBLE (-5155 970);
FORCEPROP 1 LAST PATH I148
J 0
(-5477 1100);
DISPLAY 0.872340 (-5477 1100);
PAINT GREEN (-5477 1100);
DISPLAY INVISIBLE (-5477 1100);
FORCEADD OFFPAGE..2
(-3750 1050);
FORCEPROP 2 LAST $XR0 186 
J 0
(-3561 1050);
DISPLAY 0.638298 (-3561 1050);
PAINT MONO (-3561 1050);
FORCEPROP 2 LAST $XR1 187 
J 0
(-3441 1050);
DISPLAY 0.638298 (-3441 1050);
PAINT MONO (-3441 1050);
FORCEPROP 2 LAST CDS_LIB mstr_standard
J 0
(-3750 1050);
PAINT MONO (-3750 1050);
DISPLAY INVISIBLE (-3750 1050);
FORCEPROP 1 LAST OFFPAGE TRUE
J 0
(-3425 925);
DISPLAY 0.872340 (-3425 925);
PAINT GREEN (-3425 925);
DISPLAY INVISIBLE (-3425 925);
FORCEPROP 1 LAST COMMENT_BODY TRUE
J 0
(-3795 955);
DISPLAY 0.872340 (-3795 955);
PAINT GREEN (-3795 955);
DISPLAY INVISIBLE (-3795 955);
FORCEPROP 2 LAST PATH I151
J 0
(-3575 1125);
DISPLAY 1.021277 (-3575 1125);
PAINT ORANGE (-3575 1125);
DISPLAY INVISIBLE (-3575 1125);
FORCEADD OFFPAGE..2
(-3750 2050);
FORCEPROP 2 LAST $XR0 186 
J 0
(-3561 2050);
DISPLAY 0.638298 (-3561 2050);
PAINT MONO (-3561 2050);
FORCEPROP 2 LAST $XR1 187 
J 0
(-3441 2050);
DISPLAY 0.638298 (-3441 2050);
PAINT MONO (-3441 2050);
FORCEPROP 2 LAST CDS_LIB mstr_standard
J 0
(-3750 2050);
PAINT MONO (-3750 2050);
DISPLAY INVISIBLE (-3750 2050);
FORCEPROP 1 LAST OFFPAGE TRUE
J 0
(-3425 1925);
DISPLAY 0.872340 (-3425 1925);
PAINT GREEN (-3425 1925);
DISPLAY INVISIBLE (-3425 1925);
FORCEPROP 1 LAST COMMENT_BODY TRUE
J 0
(-3795 1955);
DISPLAY 0.872340 (-3795 1955);
PAINT GREEN (-3795 1955);
DISPLAY INVISIBLE (-3795 1955);
FORCEPROP 2 LAST PATH I152
J 0
(-3575 2125);
DISPLAY 1.021277 (-3575 2125);
PAINT ORANGE (-3575 2125);
DISPLAY INVISIBLE (-3575 2125);
FORCEADD TAP..7
(-4100 2100);
FORCEPROP 3 LASTPIN (-4100 2150) SIG_NAME P3E_OCP_CPU0_PE3_C_TXP<0>
J 0
(-4090 2160);
DISPLAY 0.659574 (-4090 2160);
PAINT MONO (-4090 2160);
DISPLAY INVISIBLE (-4090 2160);
FORCEPROP 1 LASTPIN (-4100 2150) BN 0
R 1
J 0
(-4107 2098);
DISPLAY 0.617021 (-4107 2098);
PAINT GREEN (-4107 2098);
FORCEPROP 2 LAST CDS_LIB mstr_standard
J 0
(-4100 2100);
PAINT ORANGE (-4100 2100);
DISPLAY INVISIBLE (-4100 2100);
FORCEPROP 1 LAST BODY_TYPE PLUMBING
J 0
(-4050 2100);
DISPLAY 2.276596 (-4050 2100);
PAINT GREEN (-4050 2100);
DISPLAY INVISIBLE (-4050 2100);
FORCEPROP 1 LAST HDL_TAP TRUE
J 0
(-3780 1970);
DISPLAY 2.276596 (-3780 1970);
PAINT GREEN (-3780 1970);
DISPLAY INVISIBLE (-3780 1970);
FORCEPROP 1 LAST PATH I25
J 0
(-4102 2100);
DISPLAY 0.872340 (-4102 2100);
PAINT GREEN (-4102 2100);
DISPLAY INVISIBLE (-4102 2100);
FORCEADD CAP..1
R 2
(-4300 2350);
FORCEPROP 1 LAST LOCATION C1R4
J 2
(-4350 2450);
DISPLAY 0.617021 (-4350 2450);
PAINT AQUA (-4350 2450);
FORCEPROP 1 LAST PART_NUMBER A36096-155
J 2
(-4350 2200);
DISPLAY 0.617021 (-4350 2200);
PAINT BLUE (-4350 2200);
FORCEPROP 1 LAST VALUE 0.22UF
J 2
(-4350 2400);
DISPLAY 0.617021 (-4350 2400);
PAINT SKYBLUE (-4350 2400);
FORCEPROP 1 LAST TOLERANCE 10%
J 2
(-4350 2300);
DISPLAY 0.617021 (-4350 2300);
PAINT SKYBLUE (-4350 2300);
FORCEPROP 1 LAST PACK_TYPE 0402
J 2
(-4350 2150);
DISPLAY 0.617021 (-4350 2150);
PAINT SKYBLUE (-4350 2150);
FORCEPROP 1 LAST VOLTAGE 16V
J 2
(-4350 2350);
DISPLAY 0.617021 (-4350 2350);
PAINT SKYBLUE (-4350 2350);
FORCEPROP 1 LAST MATERIAL X7R
J 2
(-4350 2250);
DISPLAY 0.617021 (-4350 2250);
PAINT SKYBLUE (-4350 2250);
FORCEPROP 2 LAST BOM_COST IO_SLOT
J 0
(-4550 2500);
PAINT MONO (-4550 2500);
DISPLAY INVISIBLE (-4550 2500);
FORCEPROP 2 LAST CDS_LIB mstr_discrete
J 0
(-4300 2350);
PAINT ORANGE (-4300 2350);
DISPLAY INVISIBLE (-4300 2350);
FORCEPROP 0 LAST CDS_SEC 1
J 0
(-4350 2500);
PAINT ORANGE (-4350 2500);
DISPLAY INVISIBLE (-4350 2500);
FORCEPROP 2 LAST $SEC 1
J 0
(-4350 2550);
DISPLAY 0.680851 (-4350 2550);
PAINT MONO (-4350 2550);
DISPLAY INVISIBLE (-4350 2550);
FORCEPROP 2 LAST CDS_LOCATION C1R4
J 2
(-4350 2450);
DISPLAY 0.617021 (-4350 2450);
PAINT AQUA (-4350 2450);
DISPLAY INVISIBLE (-4350 2450);
FORCEPROP 1 LAST PATH I26
J 2
(-4350 2500);
DISPLAY 0.978723 (-4350 2500);
PAINT WHITE (-4350 2500);
DISPLAY INVISIBLE (-4350 2500);
FORCEPROP 2 LAST ROOM PCIE_STEERING
J 2
(-4300 2350);
PAINT MONO (-4300 2350);
DISPLAY INVISIBLE (-4300 2350);
FORCEPROP 1 LASTPIN (-4300 2250) $PN 2
J 2
(-4310 2230);
DISPLAY 0.787234 (-4310 2230);
PAINT ORANGE (-4310 2230);
DISPLAY INVISIBLE (-4310 2230);
FORCEPROP 1 LASTPIN (-4300 2450) $PN 1
J 2
(-4310 2430);
DISPLAY 0.787234 (-4310 2430);
PAINT ORANGE (-4310 2430);
DISPLAY INVISIBLE (-4310 2430);
FORCEADD TAP..7
(-4300 2100);
FORCEPROP 3 LASTPIN (-4300 2150) SIG_NAME P3E_OCP_CPU0_PE3_C_TXP<1>
J 0
(-4290 2160);
DISPLAY 0.659574 (-4290 2160);
PAINT MONO (-4290 2160);
DISPLAY INVISIBLE (-4290 2160);
FORCEPROP 1 LASTPIN (-4300 2150) BN 1
R 1
J 0
(-4307 2098);
DISPLAY 0.617021 (-4307 2098);
PAINT GREEN (-4307 2098);
FORCEPROP 2 LAST CDS_LIB mstr_standard
J 0
(-4300 2100);
PAINT ORANGE (-4300 2100);
DISPLAY INVISIBLE (-4300 2100);
FORCEPROP 1 LAST BODY_TYPE PLUMBING
J 0
(-4250 2100);
DISPLAY 2.276596 (-4250 2100);
PAINT GREEN (-4250 2100);
DISPLAY INVISIBLE (-4250 2100);
FORCEPROP 1 LAST HDL_TAP TRUE
J 0
(-3980 1970);
DISPLAY 2.276596 (-3980 1970);
PAINT GREEN (-3980 1970);
DISPLAY INVISIBLE (-3980 1970);
FORCEPROP 1 LAST PATH I27
J 0
(-4302 2100);
DISPLAY 0.872340 (-4302 2100);
PAINT GREEN (-4302 2100);
DISPLAY INVISIBLE (-4302 2100);
FORCEADD TAP..3
(-4075 1900);
FORCEPROP 3 LASTPIN (-4075 1850) SIG_NAME P3E_CPU0_PE3_OCP_TXN<0>
J 0
(-4065 1860);
DISPLAY 0.659574 (-4065 1860);
PAINT MONO (-4065 1860);
DISPLAY INVISIBLE (-4065 1860);
FORCEPROP 1 LASTPIN (-4075 1850) BN 0
R 1
J 0
(-4082 1838);
DISPLAY 0.617021 (-4082 1838);
PAINT GREEN (-4082 1838);
FORCEPROP 2 LAST CDS_LIB mstr_standard
J 0
(-4075 1900);
PAINT ORANGE (-4075 1900);
DISPLAY INVISIBLE (-4075 1900);
FORCEPROP 1 LAST BODY_TYPE PLUMBING
J 0
(-4025 1850);
DISPLAY 2.276596 (-4025 1850);
PAINT GREEN (-4025 1850);
DISPLAY INVISIBLE (-4025 1850);
FORCEPROP 1 LAST HDL_TAP TRUE
J 0
(-3755 1770);
DISPLAY 2.276596 (-3755 1770);
PAINT GREEN (-3755 1770);
DISPLAY INVISIBLE (-3755 1770);
FORCEPROP 1 LAST PATH I28
J 0
(-4077 1900);
DISPLAY 0.872340 (-4077 1900);
PAINT GREEN (-4077 1900);
DISPLAY INVISIBLE (-4077 1900);
FORCEADD CAP..1
R 2
(-4075 1650);
FORCEPROP 1 LAST LOCATION C1R1
J 2
(-4125 1750);
DISPLAY 0.617021 (-4125 1750);
PAINT AQUA (-4125 1750);
FORCEPROP 1 LAST PART_NUMBER A36096-155
J 2
(-4125 1500);
DISPLAY 0.617021 (-4125 1500);
PAINT BLUE (-4125 1500);
FORCEPROP 1 LAST VALUE 0.22UF
J 2
(-4125 1700);
DISPLAY 0.617021 (-4125 1700);
PAINT SKYBLUE (-4125 1700);
FORCEPROP 1 LAST TOLERANCE 10%
J 2
(-4125 1600);
DISPLAY 0.617021 (-4125 1600);
PAINT SKYBLUE (-4125 1600);
FORCEPROP 1 LAST PACK_TYPE 0402
J 2
(-4125 1450);
DISPLAY 0.617021 (-4125 1450);
PAINT SKYBLUE (-4125 1450);
FORCEPROP 1 LAST VOLTAGE 16V
J 2
(-4125 1650);
DISPLAY 0.617021 (-4125 1650);
PAINT SKYBLUE (-4125 1650);
FORCEPROP 1 LAST MATERIAL X7R
J 2
(-4125 1550);
DISPLAY 0.617021 (-4125 1550);
PAINT SKYBLUE (-4125 1550);
FORCEPROP 2 LAST BOM_COST IO_SLOT
J 0
(-4325 1800);
PAINT MONO (-4325 1800);
DISPLAY INVISIBLE (-4325 1800);
FORCEPROP 2 LAST CDS_LIB mstr_discrete
J 0
(-4075 1650);
PAINT ORANGE (-4075 1650);
DISPLAY INVISIBLE (-4075 1650);
FORCEPROP 0 LAST CDS_SEC 1
J 0
(-4125 1800);
PAINT ORANGE (-4125 1800);
DISPLAY INVISIBLE (-4125 1800);
FORCEPROP 2 LAST $SEC 1
J 0
(-4125 1850);
DISPLAY 0.680851 (-4125 1850);
PAINT MONO (-4125 1850);
DISPLAY INVISIBLE (-4125 1850);
FORCEPROP 2 LAST CDS_LOCATION C1R1
J 2
(-4125 1750);
DISPLAY 0.617021 (-4125 1750);
PAINT AQUA (-4125 1750);
DISPLAY INVISIBLE (-4125 1750);
FORCEPROP 1 LAST PATH I29
J 2
(-4125 1800);
DISPLAY 0.978723 (-4125 1800);
PAINT WHITE (-4125 1800);
DISPLAY INVISIBLE (-4125 1800);
FORCEPROP 2 LAST ROOM PCIE_STEERING
J 2
(-4075 1650);
PAINT MONO (-4075 1650);
DISPLAY INVISIBLE (-4075 1650);
FORCEPROP 1 LASTPIN (-4075 1550) $PN 2
J 2
(-4085 1530);
DISPLAY 0.787234 (-4085 1530);
PAINT ORANGE (-4085 1530);
DISPLAY INVISIBLE (-4085 1530);
FORCEPROP 1 LASTPIN (-4075 1750) $PN 1
J 2
(-4085 1730);
DISPLAY 0.787234 (-4085 1730);
PAINT ORANGE (-4085 1730);
DISPLAY INVISIBLE (-4085 1730);
FORCEADD TAP..3
(-4275 1900);
FORCEPROP 3 LASTPIN (-4275 1850) SIG_NAME P3E_CPU0_PE3_OCP_TXN<1>
J 0
(-4265 1860);
DISPLAY 0.659574 (-4265 1860);
PAINT MONO (-4265 1860);
DISPLAY INVISIBLE (-4265 1860);
FORCEPROP 1 LASTPIN (-4275 1850) BN 1
R 1
J 0
(-4282 1838);
DISPLAY 0.617021 (-4282 1838);
PAINT GREEN (-4282 1838);
FORCEPROP 2 LAST CDS_LIB mstr_standard
J 0
(-4275 1900);
PAINT ORANGE (-4275 1900);
DISPLAY INVISIBLE (-4275 1900);
FORCEPROP 1 LAST BODY_TYPE PLUMBING
J 0
(-4225 1850);
DISPLAY 2.276596 (-4225 1850);
PAINT GREEN (-4225 1850);
DISPLAY INVISIBLE (-4225 1850);
FORCEPROP 1 LAST HDL_TAP TRUE
J 0
(-3955 1770);
DISPLAY 2.276596 (-3955 1770);
PAINT GREEN (-3955 1770);
DISPLAY INVISIBLE (-3955 1770);
FORCEPROP 1 LAST PATH I30
J 0
(-4277 1900);
DISPLAY 0.872340 (-4277 1900);
PAINT GREEN (-4277 1900);
DISPLAY INVISIBLE (-4277 1900);
FORCEADD TAP..7
(-4075 1100);
FORCEPROP 3 LASTPIN (-4075 1150) SIG_NAME P3E_OCP_CPU0_PE3_C_TXN<0>
J 0
(-4065 1160);
DISPLAY 0.659574 (-4065 1160);
PAINT MONO (-4065 1160);
DISPLAY INVISIBLE (-4065 1160);
FORCEPROP 1 LASTPIN (-4075 1150) BN 0
R 1
J 0
(-4082 1098);
DISPLAY 0.617021 (-4082 1098);
PAINT GREEN (-4082 1098);
FORCEPROP 2 LAST CDS_LIB mstr_standard
J 0
(-4075 1100);
PAINT ORANGE (-4075 1100);
DISPLAY INVISIBLE (-4075 1100);
FORCEPROP 1 LAST BODY_TYPE PLUMBING
J 0
(-4025 1100);
DISPLAY 2.276596 (-4025 1100);
PAINT GREEN (-4025 1100);
DISPLAY INVISIBLE (-4025 1100);
FORCEPROP 1 LAST HDL_TAP TRUE
J 0
(-3755 970);
DISPLAY 2.276596 (-3755 970);
PAINT GREEN (-3755 970);
DISPLAY INVISIBLE (-3755 970);
FORCEPROP 1 LAST PATH I36
J 0
(-4077 1100);
DISPLAY 0.872340 (-4077 1100);
PAINT GREEN (-4077 1100);
DISPLAY INVISIBLE (-4077 1100);
FORCEADD CAP..1
R 2
(-4275 1350);
FORCEPROP 1 LAST LOCATION C1R3
J 2
(-4325 1450);
DISPLAY 0.617021 (-4325 1450);
PAINT AQUA (-4325 1450);
FORCEPROP 1 LAST PART_NUMBER A36096-155
J 2
(-4325 1200);
DISPLAY 0.617021 (-4325 1200);
PAINT BLUE (-4325 1200);
FORCEPROP 1 LAST VALUE 0.22UF
J 2
(-4325 1400);
DISPLAY 0.617021 (-4325 1400);
PAINT SKYBLUE (-4325 1400);
FORCEPROP 1 LAST TOLERANCE 10%
J 2
(-4325 1300);
DISPLAY 0.617021 (-4325 1300);
PAINT SKYBLUE (-4325 1300);
FORCEPROP 1 LAST PACK_TYPE 0402
J 2
(-4325 1150);
DISPLAY 0.617021 (-4325 1150);
PAINT SKYBLUE (-4325 1150);
FORCEPROP 1 LAST VOLTAGE 16V
J 2
(-4325 1350);
DISPLAY 0.617021 (-4325 1350);
PAINT SKYBLUE (-4325 1350);
FORCEPROP 1 LAST MATERIAL X7R
J 2
(-4325 1250);
DISPLAY 0.617021 (-4325 1250);
PAINT SKYBLUE (-4325 1250);
FORCEPROP 2 LAST BOM_COST IO_SLOT
J 0
(-4525 1500);
PAINT MONO (-4525 1500);
DISPLAY INVISIBLE (-4525 1500);
FORCEPROP 2 LAST CDS_LIB mstr_discrete
J 0
(-4275 1350);
PAINT ORANGE (-4275 1350);
DISPLAY INVISIBLE (-4275 1350);
FORCEPROP 0 LAST CDS_SEC 1
J 0
(-4325 1500);
PAINT ORANGE (-4325 1500);
DISPLAY INVISIBLE (-4325 1500);
FORCEPROP 2 LAST $SEC 1
J 0
(-4325 1550);
DISPLAY 0.680851 (-4325 1550);
PAINT MONO (-4325 1550);
DISPLAY INVISIBLE (-4325 1550);
FORCEPROP 2 LAST CDS_LOCATION C1R3
J 2
(-4325 1450);
DISPLAY 0.617021 (-4325 1450);
PAINT AQUA (-4325 1450);
DISPLAY INVISIBLE (-4325 1450);
FORCEPROP 1 LAST PATH I37
J 2
(-4325 1500);
DISPLAY 0.978723 (-4325 1500);
PAINT WHITE (-4325 1500);
DISPLAY INVISIBLE (-4325 1500);
FORCEPROP 2 LAST ROOM PCIE_STEERING
J 2
(-4275 1350);
PAINT MONO (-4275 1350);
DISPLAY INVISIBLE (-4275 1350);
FORCEPROP 1 LASTPIN (-4275 1250) $PN 2
J 2
(-4285 1230);
DISPLAY 0.787234 (-4285 1230);
PAINT ORANGE (-4285 1230);
DISPLAY INVISIBLE (-4285 1230);
FORCEPROP 1 LASTPIN (-4275 1450) $PN 1
J 2
(-4285 1430);
DISPLAY 0.787234 (-4285 1430);
PAINT ORANGE (-4285 1430);
DISPLAY INVISIBLE (-4285 1430);
FORCEADD TAP..7
(-4275 1100);
FORCEPROP 3 LASTPIN (-4275 1150) SIG_NAME P3E_OCP_CPU0_PE3_C_TXN<1>
J 0
(-4265 1160);
DISPLAY 0.659574 (-4265 1160);
PAINT MONO (-4265 1160);
DISPLAY INVISIBLE (-4265 1160);
FORCEPROP 1 LASTPIN (-4275 1150) BN 1
R 1
J 0
(-4282 1098);
DISPLAY 0.617021 (-4282 1098);
PAINT GREEN (-4282 1098);
FORCEPROP 2 LAST CDS_LIB mstr_standard
J 0
(-4275 1100);
PAINT ORANGE (-4275 1100);
DISPLAY INVISIBLE (-4275 1100);
FORCEPROP 1 LAST BODY_TYPE PLUMBING
J 0
(-4225 1100);
DISPLAY 2.276596 (-4225 1100);
PAINT GREEN (-4225 1100);
DISPLAY INVISIBLE (-4225 1100);
FORCEPROP 1 LAST HDL_TAP TRUE
J 0
(-3955 970);
DISPLAY 2.276596 (-3955 970);
PAINT GREEN (-3955 970);
DISPLAY INVISIBLE (-3955 970);
FORCEPROP 1 LAST PATH I38
J 0
(-4277 1100);
DISPLAY 0.872340 (-4277 1100);
PAINT GREEN (-4277 1100);
DISPLAY INVISIBLE (-4277 1100);
FORCEADD TAP..3
(-4500 2900);
FORCEPROP 3 LASTPIN (-4500 2850) SIG_NAME P3E_CPU0_PE3_OCP_TXP<2>
J 0
(-4490 2860);
DISPLAY 0.659574 (-4490 2860);
PAINT MONO (-4490 2860);
DISPLAY INVISIBLE (-4490 2860);
FORCEPROP 1 LASTPIN (-4500 2850) BN 2
R 1
J 0
(-4507 2838);
DISPLAY 0.617021 (-4507 2838);
PAINT GREEN (-4507 2838);
FORCEPROP 2 LAST CDS_LIB mstr_standard
J 0
(-4500 2900);
PAINT ORANGE (-4500 2900);
DISPLAY INVISIBLE (-4500 2900);
FORCEPROP 1 LAST BODY_TYPE PLUMBING
J 0
(-4450 2850);
DISPLAY 2.276596 (-4450 2850);
PAINT GREEN (-4450 2850);
DISPLAY INVISIBLE (-4450 2850);
FORCEPROP 1 LAST HDL_TAP TRUE
J 0
(-4180 2770);
DISPLAY 2.276596 (-4180 2770);
PAINT GREEN (-4180 2770);
DISPLAY INVISIBLE (-4180 2770);
FORCEPROP 1 LAST PATH I39
J 0
(-4502 2900);
DISPLAY 0.872340 (-4502 2900);
PAINT GREEN (-4502 2900);
DISPLAY INVISIBLE (-4502 2900);
FORCEADD CAP..1
R 2
(-4500 2650);
FORCEPROP 1 LAST LOCATION C1R6
J 2
(-4550 2750);
DISPLAY 0.617021 (-4550 2750);
PAINT AQUA (-4550 2750);
FORCEPROP 1 LAST PART_NUMBER A36096-155
J 2
(-4550 2500);
DISPLAY 0.617021 (-4550 2500);
PAINT BLUE (-4550 2500);
FORCEPROP 1 LAST VALUE 0.22UF
J 2
(-4550 2700);
DISPLAY 0.617021 (-4550 2700);
PAINT SKYBLUE (-4550 2700);
FORCEPROP 1 LAST TOLERANCE 10%
J 2
(-4550 2600);
DISPLAY 0.617021 (-4550 2600);
PAINT SKYBLUE (-4550 2600);
FORCEPROP 1 LAST PACK_TYPE 0402
J 2
(-4550 2450);
DISPLAY 0.617021 (-4550 2450);
PAINT SKYBLUE (-4550 2450);
FORCEPROP 1 LAST VOLTAGE 16V
J 2
(-4550 2650);
DISPLAY 0.617021 (-4550 2650);
PAINT SKYBLUE (-4550 2650);
FORCEPROP 1 LAST MATERIAL X7R
J 2
(-4550 2550);
DISPLAY 0.617021 (-4550 2550);
PAINT SKYBLUE (-4550 2550);
FORCEPROP 2 LAST CDS_LIB mstr_discrete
J 0
(-4500 2650);
PAINT ORANGE (-4500 2650);
DISPLAY INVISIBLE (-4500 2650);
FORCEPROP 0 LAST CDS_SEC 1
J 0
(-4550 2800);
PAINT ORANGE (-4550 2800);
DISPLAY INVISIBLE (-4550 2800);
FORCEPROP 2 LAST $SEC 1
J 0
(-4550 2850);
DISPLAY 0.680851 (-4550 2850);
PAINT MONO (-4550 2850);
DISPLAY INVISIBLE (-4550 2850);
FORCEPROP 2 LAST CDS_LOCATION C1R6
J 2
(-4550 2750);
DISPLAY 0.617021 (-4550 2750);
PAINT AQUA (-4550 2750);
DISPLAY INVISIBLE (-4550 2750);
FORCEPROP 1 LAST PATH I40
J 2
(-4550 2800);
DISPLAY 0.978723 (-4550 2800);
PAINT WHITE (-4550 2800);
DISPLAY INVISIBLE (-4550 2800);
FORCEPROP 2 LAST ROOM PCIE_STEERING
J 2
(-4500 2650);
PAINT MONO (-4500 2650);
DISPLAY INVISIBLE (-4500 2650);
FORCEPROP 1 LASTPIN (-4500 2550) $PN 2
J 2
(-4510 2530);
DISPLAY 0.787234 (-4510 2530);
PAINT ORANGE (-4510 2530);
DISPLAY INVISIBLE (-4510 2530);
FORCEPROP 1 LASTPIN (-4500 2750) $PN 1
J 2
(-4510 2730);
DISPLAY 0.787234 (-4510 2730);
PAINT ORANGE (-4510 2730);
DISPLAY INVISIBLE (-4510 2730);
FORCEADD TAP..3
(-4700 2900);
FORCEPROP 3 LASTPIN (-4700 2850) SIG_NAME P3E_CPU0_PE3_OCP_TXP<3>
J 0
(-4690 2860);
DISPLAY 0.659574 (-4690 2860);
PAINT MONO (-4690 2860);
DISPLAY INVISIBLE (-4690 2860);
FORCEPROP 1 LASTPIN (-4700 2850) BN 3
R 1
J 0
(-4707 2838);
DISPLAY 0.617021 (-4707 2838);
PAINT GREEN (-4707 2838);
FORCEPROP 2 LAST CDS_LIB mstr_standard
J 0
(-4700 2900);
PAINT ORANGE (-4700 2900);
DISPLAY INVISIBLE (-4700 2900);
FORCEPROP 1 LAST BODY_TYPE PLUMBING
J 0
(-4650 2850);
DISPLAY 2.276596 (-4650 2850);
PAINT GREEN (-4650 2850);
DISPLAY INVISIBLE (-4650 2850);
FORCEPROP 1 LAST HDL_TAP TRUE
J 0
(-4380 2770);
DISPLAY 2.276596 (-4380 2770);
PAINT GREEN (-4380 2770);
DISPLAY INVISIBLE (-4380 2770);
FORCEPROP 1 LAST PATH I41
J 0
(-4702 2900);
DISPLAY 0.872340 (-4702 2900);
PAINT GREEN (-4702 2900);
DISPLAY INVISIBLE (-4702 2900);
FORCEADD TAP..7
(-4500 2100);
FORCEPROP 3 LASTPIN (-4500 2150) SIG_NAME P3E_OCP_CPU0_PE3_C_TXP<2>
J 0
(-4490 2160);
DISPLAY 0.659574 (-4490 2160);
PAINT MONO (-4490 2160);
DISPLAY INVISIBLE (-4490 2160);
FORCEPROP 1 LASTPIN (-4500 2150) BN 2
R 1
J 0
(-4507 2098);
DISPLAY 0.617021 (-4507 2098);
PAINT GREEN (-4507 2098);
FORCEPROP 2 LAST CDS_LIB mstr_standard
J 0
(-4500 2100);
PAINT ORANGE (-4500 2100);
DISPLAY INVISIBLE (-4500 2100);
FORCEPROP 1 LAST BODY_TYPE PLUMBING
J 0
(-4450 2100);
DISPLAY 2.276596 (-4450 2100);
PAINT GREEN (-4450 2100);
DISPLAY INVISIBLE (-4450 2100);
FORCEPROP 1 LAST HDL_TAP TRUE
J 0
(-4180 1970);
DISPLAY 2.276596 (-4180 1970);
PAINT GREEN (-4180 1970);
DISPLAY INVISIBLE (-4180 1970);
FORCEPROP 1 LAST PATH I54
J 0
(-4502 2100);
DISPLAY 0.872340 (-4502 2100);
PAINT GREEN (-4502 2100);
DISPLAY INVISIBLE (-4502 2100);
FORCEADD CAP..1
R 2
(-4700 2350);
FORCEPROP 1 LAST LOCATION C1R8
J 2
(-4750 2450);
DISPLAY 0.617021 (-4750 2450);
PAINT AQUA (-4750 2450);
FORCEPROP 1 LAST PART_NUMBER A36096-155
J 2
(-4750 2200);
DISPLAY 0.617021 (-4750 2200);
PAINT BLUE (-4750 2200);
FORCEPROP 1 LAST VALUE 0.22UF
J 2
(-4750 2400);
DISPLAY 0.617021 (-4750 2400);
PAINT SKYBLUE (-4750 2400);
FORCEPROP 1 LAST TOLERANCE 10%
J 2
(-4750 2300);
DISPLAY 0.617021 (-4750 2300);
PAINT SKYBLUE (-4750 2300);
FORCEPROP 1 LAST PACK_TYPE 0402
J 2
(-4750 2150);
DISPLAY 0.617021 (-4750 2150);
PAINT SKYBLUE (-4750 2150);
FORCEPROP 1 LAST VOLTAGE 16V
J 2
(-4750 2350);
DISPLAY 0.617021 (-4750 2350);
PAINT SKYBLUE (-4750 2350);
FORCEPROP 1 LAST MATERIAL X7R
J 2
(-4750 2250);
DISPLAY 0.617021 (-4750 2250);
PAINT SKYBLUE (-4750 2250);
FORCEPROP 2 LAST CDS_LIB mstr_discrete
J 0
(-4700 2350);
PAINT ORANGE (-4700 2350);
DISPLAY INVISIBLE (-4700 2350);
FORCEPROP 0 LAST CDS_SEC 1
J 0
(-4750 2500);
PAINT ORANGE (-4750 2500);
DISPLAY INVISIBLE (-4750 2500);
FORCEPROP 2 LAST $SEC 1
J 0
(-4750 2550);
DISPLAY 0.680851 (-4750 2550);
PAINT MONO (-4750 2550);
DISPLAY INVISIBLE (-4750 2550);
FORCEPROP 2 LAST CDS_LOCATION C1R8
J 2
(-4750 2450);
DISPLAY 0.617021 (-4750 2450);
PAINT AQUA (-4750 2450);
DISPLAY INVISIBLE (-4750 2450);
FORCEPROP 1 LAST PATH I55
J 2
(-4750 2500);
DISPLAY 0.978723 (-4750 2500);
PAINT WHITE (-4750 2500);
DISPLAY INVISIBLE (-4750 2500);
FORCEPROP 2 LAST ROOM PCIE_STEERING
J 2
(-4700 2350);
PAINT MONO (-4700 2350);
DISPLAY INVISIBLE (-4700 2350);
FORCEPROP 1 LASTPIN (-4700 2250) $PN 2
J 2
(-4710 2230);
DISPLAY 0.787234 (-4710 2230);
PAINT ORANGE (-4710 2230);
DISPLAY INVISIBLE (-4710 2230);
FORCEPROP 1 LASTPIN (-4700 2450) $PN 1
J 2
(-4710 2430);
DISPLAY 0.787234 (-4710 2430);
PAINT ORANGE (-4710 2430);
DISPLAY INVISIBLE (-4710 2430);
FORCEADD TAP..7
(-4700 2100);
FORCEPROP 3 LASTPIN (-4700 2150) SIG_NAME P3E_OCP_CPU0_PE3_C_TXP<3>
J 0
(-4690 2160);
DISPLAY 0.659574 (-4690 2160);
PAINT MONO (-4690 2160);
DISPLAY INVISIBLE (-4690 2160);
FORCEPROP 1 LASTPIN (-4700 2150) BN 3
R 1
J 0
(-4707 2098);
DISPLAY 0.617021 (-4707 2098);
PAINT GREEN (-4707 2098);
FORCEPROP 2 LAST CDS_LIB mstr_standard
J 0
(-4700 2100);
PAINT ORANGE (-4700 2100);
DISPLAY INVISIBLE (-4700 2100);
FORCEPROP 1 LAST BODY_TYPE PLUMBING
J 0
(-4650 2100);
DISPLAY 2.276596 (-4650 2100);
PAINT GREEN (-4650 2100);
DISPLAY INVISIBLE (-4650 2100);
FORCEPROP 1 LAST HDL_TAP TRUE
J 0
(-4380 1970);
DISPLAY 2.276596 (-4380 1970);
PAINT GREEN (-4380 1970);
DISPLAY INVISIBLE (-4380 1970);
FORCEPROP 1 LAST PATH I56
J 0
(-4702 2100);
DISPLAY 0.872340 (-4702 2100);
PAINT GREEN (-4702 2100);
DISPLAY INVISIBLE (-4702 2100);
FORCEADD TAP..3
(-4475 1900);
FORCEPROP 3 LASTPIN (-4475 1850) SIG_NAME P3E_CPU0_PE3_OCP_TXN<2>
J 0
(-4465 1860);
DISPLAY 0.659574 (-4465 1860);
PAINT MONO (-4465 1860);
DISPLAY INVISIBLE (-4465 1860);
FORCEPROP 1 LASTPIN (-4475 1850) BN 2
R 1
J 0
(-4482 1838);
DISPLAY 0.617021 (-4482 1838);
PAINT GREEN (-4482 1838);
FORCEPROP 2 LAST CDS_LIB mstr_standard
J 0
(-4475 1900);
PAINT ORANGE (-4475 1900);
DISPLAY INVISIBLE (-4475 1900);
FORCEPROP 1 LAST BODY_TYPE PLUMBING
J 0
(-4425 1850);
DISPLAY 2.276596 (-4425 1850);
PAINT GREEN (-4425 1850);
DISPLAY INVISIBLE (-4425 1850);
FORCEPROP 1 LAST HDL_TAP TRUE
J 0
(-4155 1770);
DISPLAY 2.276596 (-4155 1770);
PAINT GREEN (-4155 1770);
DISPLAY INVISIBLE (-4155 1770);
FORCEPROP 1 LAST PATH I58
J 0
(-4477 1900);
DISPLAY 0.872340 (-4477 1900);
PAINT GREEN (-4477 1900);
DISPLAY INVISIBLE (-4477 1900);
FORCEADD CAP..1
R 2
(-4475 1650);
FORCEPROP 1 LAST LOCATION C1R5
J 2
(-4525 1750);
DISPLAY 0.617021 (-4525 1750);
PAINT AQUA (-4525 1750);
FORCEPROP 1 LAST PART_NUMBER A36096-155
J 2
(-4525 1500);
DISPLAY 0.617021 (-4525 1500);
PAINT BLUE (-4525 1500);
FORCEPROP 1 LAST VALUE 0.22UF
J 2
(-4525 1700);
DISPLAY 0.617021 (-4525 1700);
PAINT SKYBLUE (-4525 1700);
FORCEPROP 1 LAST TOLERANCE 10%
J 2
(-4525 1600);
DISPLAY 0.617021 (-4525 1600);
PAINT SKYBLUE (-4525 1600);
FORCEPROP 1 LAST PACK_TYPE 0402
J 2
(-4525 1450);
DISPLAY 0.617021 (-4525 1450);
PAINT SKYBLUE (-4525 1450);
FORCEPROP 1 LAST VOLTAGE 16V
J 2
(-4525 1650);
DISPLAY 0.617021 (-4525 1650);
PAINT SKYBLUE (-4525 1650);
FORCEPROP 1 LAST MATERIAL X7R
J 2
(-4525 1550);
DISPLAY 0.617021 (-4525 1550);
PAINT SKYBLUE (-4525 1550);
FORCEPROP 2 LAST BOM_COST IO_SLOT
J 0
(-4725 1800);
PAINT MONO (-4725 1800);
DISPLAY INVISIBLE (-4725 1800);
FORCEPROP 2 LAST CDS_LIB mstr_discrete
J 0
(-4475 1650);
PAINT ORANGE (-4475 1650);
DISPLAY INVISIBLE (-4475 1650);
FORCEPROP 0 LAST CDS_SEC 1
J 0
(-4525 1800);
PAINT ORANGE (-4525 1800);
DISPLAY INVISIBLE (-4525 1800);
FORCEPROP 2 LAST $SEC 1
J 0
(-4525 1850);
DISPLAY 0.680851 (-4525 1850);
PAINT MONO (-4525 1850);
DISPLAY INVISIBLE (-4525 1850);
FORCEPROP 2 LAST CDS_LOCATION C1R5
J 2
(-4525 1750);
DISPLAY 0.617021 (-4525 1750);
PAINT AQUA (-4525 1750);
DISPLAY INVISIBLE (-4525 1750);
FORCEPROP 1 LAST PATH I59
J 2
(-4525 1800);
DISPLAY 0.978723 (-4525 1800);
PAINT WHITE (-4525 1800);
DISPLAY INVISIBLE (-4525 1800);
FORCEPROP 2 LAST ROOM PCIE_STEERING
J 2
(-4475 1650);
PAINT MONO (-4475 1650);
DISPLAY INVISIBLE (-4475 1650);
FORCEPROP 1 LASTPIN (-4475 1550) $PN 2
J 2
(-4485 1530);
DISPLAY 0.787234 (-4485 1530);
PAINT ORANGE (-4485 1530);
DISPLAY INVISIBLE (-4485 1530);
FORCEPROP 1 LASTPIN (-4475 1750) $PN 1
J 2
(-4485 1730);
DISPLAY 0.787234 (-4485 1730);
PAINT ORANGE (-4485 1730);
DISPLAY INVISIBLE (-4485 1730);
FORCEADD TAP..3
(-4675 1900);
FORCEPROP 3 LASTPIN (-4675 1850) SIG_NAME P3E_CPU0_PE3_OCP_TXN<3>
J 0
(-4665 1860);
DISPLAY 0.659574 (-4665 1860);
PAINT MONO (-4665 1860);
DISPLAY INVISIBLE (-4665 1860);
FORCEPROP 1 LASTPIN (-4675 1850) BN 3
R 1
J 0
(-4682 1838);
DISPLAY 0.617021 (-4682 1838);
PAINT GREEN (-4682 1838);
FORCEPROP 2 LAST CDS_LIB mstr_standard
J 0
(-4675 1900);
PAINT ORANGE (-4675 1900);
DISPLAY INVISIBLE (-4675 1900);
FORCEPROP 1 LAST BODY_TYPE PLUMBING
J 0
(-4625 1850);
DISPLAY 2.276596 (-4625 1850);
PAINT GREEN (-4625 1850);
DISPLAY INVISIBLE (-4625 1850);
FORCEPROP 1 LAST HDL_TAP TRUE
J 0
(-4355 1770);
DISPLAY 2.276596 (-4355 1770);
PAINT GREEN (-4355 1770);
DISPLAY INVISIBLE (-4355 1770);
FORCEPROP 1 LAST PATH I60
J 0
(-4677 1900);
DISPLAY 0.872340 (-4677 1900);
PAINT GREEN (-4677 1900);
DISPLAY INVISIBLE (-4677 1900);
FORCEADD TAP..7
(-4475 1100);
FORCEPROP 3 LASTPIN (-4475 1150) SIG_NAME P3E_OCP_CPU0_PE3_C_TXN<2>
J 0
(-4465 1160);
DISPLAY 0.659574 (-4465 1160);
PAINT MONO (-4465 1160);
DISPLAY INVISIBLE (-4465 1160);
FORCEPROP 1 LASTPIN (-4475 1150) BN 2
R 1
J 0
(-4482 1098);
DISPLAY 0.617021 (-4482 1098);
PAINT GREEN (-4482 1098);
FORCEPROP 2 LAST CDS_LIB mstr_standard
J 0
(-4475 1100);
PAINT ORANGE (-4475 1100);
DISPLAY INVISIBLE (-4475 1100);
FORCEPROP 1 LAST BODY_TYPE PLUMBING
J 0
(-4425 1100);
DISPLAY 2.276596 (-4425 1100);
PAINT GREEN (-4425 1100);
DISPLAY INVISIBLE (-4425 1100);
FORCEPROP 1 LAST HDL_TAP TRUE
J 0
(-4155 970);
DISPLAY 2.276596 (-4155 970);
PAINT GREEN (-4155 970);
DISPLAY INVISIBLE (-4155 970);
FORCEPROP 1 LAST PATH I69
J 0
(-4477 1100);
DISPLAY 0.872340 (-4477 1100);
PAINT GREEN (-4477 1100);
DISPLAY INVISIBLE (-4477 1100);
FORCEADD CAP..1
R 2
(-4675 1350);
FORCEPROP 1 LAST LOCATION C1R7
J 2
(-4725 1450);
DISPLAY 0.617021 (-4725 1450);
PAINT AQUA (-4725 1450);
FORCEPROP 1 LAST PART_NUMBER A36096-155
J 2
(-4725 1200);
DISPLAY 0.617021 (-4725 1200);
PAINT BLUE (-4725 1200);
FORCEPROP 1 LAST VALUE 0.22UF
J 2
(-4725 1400);
DISPLAY 0.617021 (-4725 1400);
PAINT SKYBLUE (-4725 1400);
FORCEPROP 1 LAST TOLERANCE 10%
J 2
(-4725 1300);
DISPLAY 0.617021 (-4725 1300);
PAINT SKYBLUE (-4725 1300);
FORCEPROP 1 LAST PACK_TYPE 0402
J 2
(-4725 1150);
DISPLAY 0.617021 (-4725 1150);
PAINT SKYBLUE (-4725 1150);
FORCEPROP 1 LAST VOLTAGE 16V
J 2
(-4725 1350);
DISPLAY 0.617021 (-4725 1350);
PAINT SKYBLUE (-4725 1350);
FORCEPROP 1 LAST MATERIAL X7R
J 2
(-4725 1250);
DISPLAY 0.617021 (-4725 1250);
PAINT SKYBLUE (-4725 1250);
FORCEPROP 2 LAST BOM_COST IO_SLOT
J 0
(-4925 1500);
PAINT MONO (-4925 1500);
DISPLAY INVISIBLE (-4925 1500);
FORCEPROP 2 LAST CDS_LIB mstr_discrete
J 0
(-4675 1350);
PAINT ORANGE (-4675 1350);
DISPLAY INVISIBLE (-4675 1350);
FORCEPROP 0 LAST CDS_SEC 1
J 0
(-4725 1500);
PAINT ORANGE (-4725 1500);
DISPLAY INVISIBLE (-4725 1500);
FORCEPROP 2 LAST $SEC 1
J 0
(-4725 1550);
DISPLAY 0.680851 (-4725 1550);
PAINT MONO (-4725 1550);
DISPLAY INVISIBLE (-4725 1550);
FORCEPROP 2 LAST CDS_LOCATION C1R7
J 2
(-4725 1450);
DISPLAY 0.617021 (-4725 1450);
PAINT AQUA (-4725 1450);
DISPLAY INVISIBLE (-4725 1450);
FORCEPROP 1 LAST PATH I70
J 2
(-4725 1500);
DISPLAY 0.978723 (-4725 1500);
PAINT WHITE (-4725 1500);
DISPLAY INVISIBLE (-4725 1500);
FORCEPROP 2 LAST ROOM PCIE_STEERING
J 2
(-4675 1350);
PAINT MONO (-4675 1350);
DISPLAY INVISIBLE (-4675 1350);
FORCEPROP 1 LASTPIN (-4675 1250) $PN 2
J 2
(-4685 1230);
DISPLAY 0.787234 (-4685 1230);
PAINT ORANGE (-4685 1230);
DISPLAY INVISIBLE (-4685 1230);
FORCEPROP 1 LASTPIN (-4675 1450) $PN 1
J 2
(-4685 1430);
DISPLAY 0.787234 (-4685 1430);
PAINT ORANGE (-4685 1430);
DISPLAY INVISIBLE (-4685 1430);
FORCEADD TAP..7
(-4675 1100);
FORCEPROP 3 LASTPIN (-4675 1150) SIG_NAME P3E_OCP_CPU0_PE3_C_TXN<3>
J 0
(-4665 1160);
DISPLAY 0.659574 (-4665 1160);
PAINT MONO (-4665 1160);
DISPLAY INVISIBLE (-4665 1160);
FORCEPROP 1 LASTPIN (-4675 1150) BN 3
R 1
J 0
(-4682 1098);
DISPLAY 0.617021 (-4682 1098);
PAINT GREEN (-4682 1098);
FORCEPROP 2 LAST CDS_LIB mstr_standard
J 0
(-4675 1100);
PAINT ORANGE (-4675 1100);
DISPLAY INVISIBLE (-4675 1100);
FORCEPROP 1 LAST BODY_TYPE PLUMBING
J 0
(-4625 1100);
DISPLAY 2.276596 (-4625 1100);
PAINT GREEN (-4625 1100);
DISPLAY INVISIBLE (-4625 1100);
FORCEPROP 1 LAST HDL_TAP TRUE
J 0
(-4355 970);
DISPLAY 2.276596 (-4355 970);
PAINT GREEN (-4355 970);
DISPLAY INVISIBLE (-4355 970);
FORCEPROP 1 LAST PATH I72
J 0
(-4677 1100);
DISPLAY 0.872340 (-4677 1100);
PAINT GREEN (-4677 1100);
DISPLAY INVISIBLE (-4677 1100);
FORCEADD TAP..7
(-5900 2100);
FORCEPROP 3 LASTPIN (-5900 2150) SIG_NAME P3E_OCP_CPU0_PE3_C_TXP<9>
J 0
(-5890 2160);
DISPLAY 0.659574 (-5890 2160);
PAINT MONO (-5890 2160);
DISPLAY INVISIBLE (-5890 2160);
FORCEPROP 1 LASTPIN (-5900 2150) BN 9
R 1
J 0
(-5907 2098);
DISPLAY 0.617021 (-5907 2098);
PAINT GREEN (-5907 2098);
FORCEPROP 2 LAST CDS_LIB mstr_standard
J 0
(-5900 2100);
PAINT ORANGE (-5900 2100);
DISPLAY INVISIBLE (-5900 2100);
FORCEPROP 1 LAST BODY_TYPE PLUMBING
J 0
(-5850 2100);
DISPLAY 2.276596 (-5850 2100);
PAINT GREEN (-5850 2100);
DISPLAY INVISIBLE (-5850 2100);
FORCEPROP 1 LAST HDL_TAP TRUE
J 0
(-5580 1970);
DISPLAY 2.276596 (-5580 1970);
PAINT GREEN (-5580 1970);
DISPLAY INVISIBLE (-5580 1970);
FORCEPROP 1 LAST PATH I73
J 0
(-5902 2100);
DISPLAY 0.872340 (-5902 2100);
PAINT GREEN (-5902 2100);
DISPLAY INVISIBLE (-5902 2100);
FORCEADD TAP..7
(-5650 1100);
FORCEPROP 3 LASTPIN (-5650 1150) SIG_NAME P3E_OCP_CPU0_PE3_C_TXN<8>
J 0
(-5640 1160);
DISPLAY 0.659574 (-5640 1160);
PAINT MONO (-5640 1160);
DISPLAY INVISIBLE (-5640 1160);
FORCEPROP 1 LASTPIN (-5650 1150) BN 8
R 1
J 0
(-5657 1098);
DISPLAY 0.617021 (-5657 1098);
PAINT GREEN (-5657 1098);
FORCEPROP 2 LAST CDS_LIB mstr_standard
J 0
(-5650 1100);
PAINT ORANGE (-5650 1100);
DISPLAY INVISIBLE (-5650 1100);
FORCEPROP 1 LAST BODY_TYPE PLUMBING
J 0
(-5600 1100);
DISPLAY 2.276596 (-5600 1100);
PAINT GREEN (-5600 1100);
DISPLAY INVISIBLE (-5600 1100);
FORCEPROP 1 LAST HDL_TAP TRUE
J 0
(-5330 970);
DISPLAY 2.276596 (-5330 970);
PAINT GREEN (-5330 970);
DISPLAY INVISIBLE (-5330 970);
FORCEPROP 1 LAST PATH I74
J 0
(-5652 1100);
DISPLAY 0.872340 (-5652 1100);
PAINT GREEN (-5652 1100);
DISPLAY INVISIBLE (-5652 1100);
FORCEADD TAP..3
(-5700 2900);
FORCEPROP 3 LASTPIN (-5700 2850) SIG_NAME P3E_CPU0_PE3_OCP_TXP<8>
J 0
(-5690 2860);
DISPLAY 0.659574 (-5690 2860);
PAINT MONO (-5690 2860);
DISPLAY INVISIBLE (-5690 2860);
FORCEPROP 1 LASTPIN (-5700 2850) BN 8
R 1
J 0
(-5707 2838);
DISPLAY 0.617021 (-5707 2838);
PAINT GREEN (-5707 2838);
FORCEPROP 2 LAST CDS_LIB mstr_standard
J 0
(-5700 2900);
PAINT ORANGE (-5700 2900);
DISPLAY INVISIBLE (-5700 2900);
FORCEPROP 1 LAST BODY_TYPE PLUMBING
J 0
(-5650 2850);
DISPLAY 2.276596 (-5650 2850);
PAINT GREEN (-5650 2850);
DISPLAY INVISIBLE (-5650 2850);
FORCEPROP 1 LAST HDL_TAP TRUE
J 0
(-5380 2770);
DISPLAY 2.276596 (-5380 2770);
PAINT GREEN (-5380 2770);
DISPLAY INVISIBLE (-5380 2770);
FORCEPROP 1 LAST PATH I75
J 0
(-5702 2900);
DISPLAY 0.872340 (-5702 2900);
PAINT GREEN (-5702 2900);
DISPLAY INVISIBLE (-5702 2900);
FORCEADD CAP..1
R 2
(-5700 2650);
FORCEPROP 1 LAST LOCATION C2M14
J 2
(-5750 2750);
DISPLAY 0.617021 (-5750 2750);
PAINT AQUA (-5750 2750);
FORCEPROP 1 LAST PART_NUMBER A36096-155
J 2
(-5750 2500);
DISPLAY 0.617021 (-5750 2500);
PAINT BLUE (-5750 2500);
FORCEPROP 1 LAST VALUE 0.22UF
J 2
(-5750 2700);
DISPLAY 0.617021 (-5750 2700);
PAINT SKYBLUE (-5750 2700);
FORCEPROP 1 LAST TOLERANCE 10%
J 2
(-5750 2600);
DISPLAY 0.617021 (-5750 2600);
PAINT SKYBLUE (-5750 2600);
FORCEPROP 1 LAST PACK_TYPE 0402
J 2
(-5750 2450);
DISPLAY 0.617021 (-5750 2450);
PAINT SKYBLUE (-5750 2450);
FORCEPROP 1 LAST VOLTAGE 16V
J 2
(-5750 2650);
DISPLAY 0.617021 (-5750 2650);
PAINT SKYBLUE (-5750 2650);
FORCEPROP 1 LAST MATERIAL X7R
J 2
(-5750 2550);
DISPLAY 0.617021 (-5750 2550);
PAINT SKYBLUE (-5750 2550);
FORCEPROP 2 LAST CDS_LIB mstr_discrete
J 0
(-5700 2650);
PAINT ORANGE (-5700 2650);
DISPLAY INVISIBLE (-5700 2650);
FORCEPROP 2 LAST BOM_COST IO_SLOT
J 0
(-5950 2800);
PAINT MONO (-5950 2800);
DISPLAY INVISIBLE (-5950 2800);
FORCEPROP 0 LAST CDS_SEC 1
J 0
(-5750 2800);
PAINT ORANGE (-5750 2800);
DISPLAY INVISIBLE (-5750 2800);
FORCEPROP 2 LAST $SEC 1
J 0
(-5750 2850);
DISPLAY 0.680851 (-5750 2850);
PAINT MONO (-5750 2850);
DISPLAY INVISIBLE (-5750 2850);
FORCEPROP 2 LAST CDS_LOCATION C2M14
J 2
(-5750 2750);
DISPLAY 0.617021 (-5750 2750);
PAINT AQUA (-5750 2750);
DISPLAY INVISIBLE (-5750 2750);
FORCEPROP 1 LAST PATH I76
J 2
(-5750 2800);
DISPLAY 0.978723 (-5750 2800);
PAINT WHITE (-5750 2800);
DISPLAY INVISIBLE (-5750 2800);
FORCEPROP 2 LAST ROOM PCIE_STEERING
J 2
(-5700 2650);
PAINT MONO (-5700 2650);
DISPLAY INVISIBLE (-5700 2650);
FORCEPROP 1 LASTPIN (-5700 2550) $PN 2
J 2
(-5710 2530);
DISPLAY 0.787234 (-5710 2530);
PAINT ORANGE (-5710 2530);
DISPLAY INVISIBLE (-5710 2530);
FORCEPROP 1 LASTPIN (-5700 2750) $PN 1
J 2
(-5710 2730);
DISPLAY 0.787234 (-5710 2730);
PAINT ORANGE (-5710 2730);
DISPLAY INVISIBLE (-5710 2730);
FORCEADD TAP..7
(-5700 2100);
FORCEPROP 3 LASTPIN (-5700 2150) SIG_NAME P3E_OCP_CPU0_PE3_C_TXP<8>
J 0
(-5690 2160);
DISPLAY 0.659574 (-5690 2160);
PAINT MONO (-5690 2160);
DISPLAY INVISIBLE (-5690 2160);
FORCEPROP 1 LASTPIN (-5700 2150) BN 8
R 1
J 0
(-5707 2098);
DISPLAY 0.617021 (-5707 2098);
PAINT GREEN (-5707 2098);
FORCEPROP 2 LAST CDS_LIB mstr_standard
J 0
(-5700 2100);
PAINT ORANGE (-5700 2100);
DISPLAY INVISIBLE (-5700 2100);
FORCEPROP 1 LAST BODY_TYPE PLUMBING
J 0
(-5650 2100);
DISPLAY 2.276596 (-5650 2100);
PAINT GREEN (-5650 2100);
DISPLAY INVISIBLE (-5650 2100);
FORCEPROP 1 LAST HDL_TAP TRUE
J 0
(-5380 1970);
DISPLAY 2.276596 (-5380 1970);
PAINT GREEN (-5380 1970);
DISPLAY INVISIBLE (-5380 1970);
FORCEPROP 1 LAST PATH I77
J 0
(-5702 2100);
DISPLAY 0.872340 (-5702 2100);
PAINT GREEN (-5702 2100);
DISPLAY INVISIBLE (-5702 2100);
FORCEADD CAP..1
R 2
(-5900 2350);
FORCEPROP 1 LAST LOCATION C1M18
J 2
(-5950 2450);
DISPLAY 0.617021 (-5950 2450);
PAINT AQUA (-5950 2450);
FORCEPROP 1 LAST PART_NUMBER A36096-155
J 2
(-5950 2200);
DISPLAY 0.617021 (-5950 2200);
PAINT BLUE (-5950 2200);
FORCEPROP 1 LAST VALUE 0.22UF
J 2
(-5950 2400);
DISPLAY 0.617021 (-5950 2400);
PAINT SKYBLUE (-5950 2400);
FORCEPROP 1 LAST TOLERANCE 10%
J 2
(-5950 2300);
DISPLAY 0.617021 (-5950 2300);
PAINT SKYBLUE (-5950 2300);
FORCEPROP 1 LAST PACK_TYPE 0402
J 2
(-5950 2150);
DISPLAY 0.617021 (-5950 2150);
PAINT SKYBLUE (-5950 2150);
FORCEPROP 1 LAST VOLTAGE 16V
J 2
(-5950 2350);
DISPLAY 0.617021 (-5950 2350);
PAINT SKYBLUE (-5950 2350);
FORCEPROP 1 LAST MATERIAL X7R
J 2
(-5950 2250);
DISPLAY 0.617021 (-5950 2250);
PAINT SKYBLUE (-5950 2250);
FORCEPROP 2 LAST CDS_LIB mstr_discrete
J 0
(-5900 2350);
PAINT ORANGE (-5900 2350);
DISPLAY INVISIBLE (-5900 2350);
FORCEPROP 2 LAST BOM_COST IO_SLOT
J 0
(-6150 2500);
PAINT MONO (-6150 2500);
DISPLAY INVISIBLE (-6150 2500);
FORCEPROP 0 LAST CDS_SEC 1
J 0
(-5950 2500);
PAINT ORANGE (-5950 2500);
DISPLAY INVISIBLE (-5950 2500);
FORCEPROP 2 LAST $SEC 1
J 0
(-5950 2550);
DISPLAY 0.680851 (-5950 2550);
PAINT MONO (-5950 2550);
DISPLAY INVISIBLE (-5950 2550);
FORCEPROP 2 LAST CDS_LOCATION C1M18
J 2
(-5950 2450);
DISPLAY 0.617021 (-5950 2450);
PAINT AQUA (-5950 2450);
DISPLAY INVISIBLE (-5950 2450);
FORCEPROP 1 LAST PATH I78
J 2
(-5950 2500);
DISPLAY 0.978723 (-5950 2500);
PAINT WHITE (-5950 2500);
DISPLAY INVISIBLE (-5950 2500);
FORCEPROP 2 LAST ROOM PCIE_STEERING
J 2
(-5900 2350);
PAINT MONO (-5900 2350);
DISPLAY INVISIBLE (-5900 2350);
FORCEPROP 1 LASTPIN (-5900 2250) $PN 2
J 2
(-5910 2230);
DISPLAY 0.787234 (-5910 2230);
PAINT ORANGE (-5910 2230);
DISPLAY INVISIBLE (-5910 2230);
FORCEPROP 1 LASTPIN (-5900 2450) $PN 1
J 2
(-5910 2430);
DISPLAY 0.787234 (-5910 2430);
PAINT ORANGE (-5910 2430);
DISPLAY INVISIBLE (-5910 2430);
FORCEADD TAP..3
(-5900 2900);
FORCEPROP 3 LASTPIN (-5900 2850) SIG_NAME P3E_CPU0_PE3_OCP_TXP<9>
J 0
(-5890 2860);
DISPLAY 0.659574 (-5890 2860);
PAINT MONO (-5890 2860);
DISPLAY INVISIBLE (-5890 2860);
FORCEPROP 1 LASTPIN (-5900 2850) BN 9
R 1
J 0
(-5907 2838);
DISPLAY 0.617021 (-5907 2838);
PAINT GREEN (-5907 2838);
FORCEPROP 2 LAST CDS_LIB mstr_standard
J 0
(-5900 2900);
PAINT ORANGE (-5900 2900);
DISPLAY INVISIBLE (-5900 2900);
FORCEPROP 1 LAST BODY_TYPE PLUMBING
J 0
(-5850 2850);
DISPLAY 2.276596 (-5850 2850);
PAINT GREEN (-5850 2850);
DISPLAY INVISIBLE (-5850 2850);
FORCEPROP 1 LAST HDL_TAP TRUE
J 0
(-5580 2770);
DISPLAY 2.276596 (-5580 2770);
PAINT GREEN (-5580 2770);
DISPLAY INVISIBLE (-5580 2770);
FORCEPROP 1 LAST PATH I79
J 0
(-5902 2900);
DISPLAY 0.872340 (-5902 2900);
PAINT GREEN (-5902 2900);
DISPLAY INVISIBLE (-5902 2900);
FORCEADD TAP..3
(-6100 2900);
FORCEPROP 3 LASTPIN (-6100 2850) SIG_NAME P3E_CPU0_PE3_OCP_TXP<10>
J 0
(-6090 2860);
DISPLAY 0.659574 (-6090 2860);
PAINT MONO (-6090 2860);
DISPLAY INVISIBLE (-6090 2860);
FORCEPROP 1 LASTPIN (-6100 2850) BN 10
R 1
J 0
(-6107 2838);
DISPLAY 0.617021 (-6107 2838);
PAINT GREEN (-6107 2838);
FORCEPROP 2 LAST CDS_LIB mstr_standard
J 0
(-6100 2900);
PAINT ORANGE (-6100 2900);
DISPLAY INVISIBLE (-6100 2900);
FORCEPROP 1 LAST BODY_TYPE PLUMBING
J 0
(-6050 2850);
DISPLAY 2.276596 (-6050 2850);
PAINT GREEN (-6050 2850);
DISPLAY INVISIBLE (-6050 2850);
FORCEPROP 1 LAST HDL_TAP TRUE
J 0
(-5780 2770);
DISPLAY 2.276596 (-5780 2770);
PAINT GREEN (-5780 2770);
DISPLAY INVISIBLE (-5780 2770);
FORCEPROP 1 LAST PATH I80
J 0
(-6102 2900);
DISPLAY 0.872340 (-6102 2900);
PAINT GREEN (-6102 2900);
DISPLAY INVISIBLE (-6102 2900);
FORCEADD TAP..3
(-6300 2900);
FORCEPROP 3 LASTPIN (-6300 2850) SIG_NAME P3E_CPU0_PE3_OCP_TXP<11>
J 0
(-6290 2860);
DISPLAY 0.659574 (-6290 2860);
PAINT MONO (-6290 2860);
DISPLAY INVISIBLE (-6290 2860);
FORCEPROP 1 LASTPIN (-6300 2850) BN 11
R 1
J 0
(-6307 2838);
DISPLAY 0.617021 (-6307 2838);
PAINT GREEN (-6307 2838);
FORCEPROP 2 LAST CDS_LIB mstr_standard
J 0
(-6300 2900);
PAINT ORANGE (-6300 2900);
DISPLAY INVISIBLE (-6300 2900);
FORCEPROP 1 LAST BODY_TYPE PLUMBING
J 0
(-6250 2850);
DISPLAY 2.276596 (-6250 2850);
PAINT GREEN (-6250 2850);
DISPLAY INVISIBLE (-6250 2850);
FORCEPROP 1 LAST HDL_TAP TRUE
J 0
(-5980 2770);
DISPLAY 2.276596 (-5980 2770);
PAINT GREEN (-5980 2770);
DISPLAY INVISIBLE (-5980 2770);
FORCEPROP 1 LAST PATH I81
J 0
(-6302 2900);
DISPLAY 0.872340 (-6302 2900);
PAINT GREEN (-6302 2900);
DISPLAY INVISIBLE (-6302 2900);
FORCEADD CAP..1
R 2
(-6100 2650);
FORCEPROP 1 LAST LOCATION C1M16
J 2
(-6150 2750);
DISPLAY 0.617021 (-6150 2750);
PAINT AQUA (-6150 2750);
FORCEPROP 1 LAST PART_NUMBER A36096-155
J 2
(-6150 2500);
DISPLAY 0.617021 (-6150 2500);
PAINT BLUE (-6150 2500);
FORCEPROP 1 LAST VALUE 0.22UF
J 2
(-6150 2700);
DISPLAY 0.617021 (-6150 2700);
PAINT SKYBLUE (-6150 2700);
FORCEPROP 1 LAST TOLERANCE 10%
J 2
(-6150 2600);
DISPLAY 0.617021 (-6150 2600);
PAINT SKYBLUE (-6150 2600);
FORCEPROP 1 LAST PACK_TYPE 0402
J 2
(-6150 2450);
DISPLAY 0.617021 (-6150 2450);
PAINT SKYBLUE (-6150 2450);
FORCEPROP 1 LAST VOLTAGE 16V
J 2
(-6150 2650);
DISPLAY 0.617021 (-6150 2650);
PAINT SKYBLUE (-6150 2650);
FORCEPROP 1 LAST MATERIAL X7R
J 2
(-6150 2550);
DISPLAY 0.617021 (-6150 2550);
PAINT SKYBLUE (-6150 2550);
FORCEPROP 2 LAST CDS_LIB mstr_discrete
J 0
(-6100 2650);
PAINT ORANGE (-6100 2650);
DISPLAY INVISIBLE (-6100 2650);
FORCEPROP 2 LAST BOM_COST IO_SLOT
J 0
(-6350 2800);
PAINT MONO (-6350 2800);
DISPLAY INVISIBLE (-6350 2800);
FORCEPROP 0 LAST CDS_SEC 1
J 0
(-6150 2800);
PAINT ORANGE (-6150 2800);
DISPLAY INVISIBLE (-6150 2800);
FORCEPROP 2 LAST $SEC 1
J 0
(-6150 2850);
DISPLAY 0.680851 (-6150 2850);
PAINT MONO (-6150 2850);
DISPLAY INVISIBLE (-6150 2850);
FORCEPROP 2 LAST CDS_LOCATION C1M16
J 2
(-6150 2750);
DISPLAY 0.617021 (-6150 2750);
PAINT AQUA (-6150 2750);
DISPLAY INVISIBLE (-6150 2750);
FORCEPROP 1 LAST PATH I82
J 2
(-6150 2800);
DISPLAY 0.978723 (-6150 2800);
PAINT WHITE (-6150 2800);
DISPLAY INVISIBLE (-6150 2800);
FORCEPROP 2 LAST ROOM PCIE_STEERING
J 2
(-6100 2650);
PAINT MONO (-6100 2650);
DISPLAY INVISIBLE (-6100 2650);
FORCEPROP 1 LASTPIN (-6100 2550) $PN 2
J 2
(-6110 2530);
DISPLAY 0.787234 (-6110 2530);
PAINT ORANGE (-6110 2530);
DISPLAY INVISIBLE (-6110 2530);
FORCEPROP 1 LASTPIN (-6100 2750) $PN 1
J 2
(-6110 2730);
DISPLAY 0.787234 (-6110 2730);
PAINT ORANGE (-6110 2730);
DISPLAY INVISIBLE (-6110 2730);
FORCEADD TAP..7
(-6100 2100);
FORCEPROP 3 LASTPIN (-6100 2150) SIG_NAME P3E_OCP_CPU0_PE3_C_TXP<10>
J 0
(-6090 2160);
DISPLAY 0.659574 (-6090 2160);
PAINT MONO (-6090 2160);
DISPLAY INVISIBLE (-6090 2160);
FORCEPROP 1 LASTPIN (-6100 2150) BN 10
R 1
J 0
(-6107 2098);
DISPLAY 0.617021 (-6107 2098);
PAINT GREEN (-6107 2098);
FORCEPROP 2 LAST CDS_LIB mstr_standard
J 0
(-6100 2100);
PAINT ORANGE (-6100 2100);
DISPLAY INVISIBLE (-6100 2100);
FORCEPROP 1 LAST BODY_TYPE PLUMBING
J 0
(-6050 2100);
DISPLAY 2.276596 (-6050 2100);
PAINT GREEN (-6050 2100);
DISPLAY INVISIBLE (-6050 2100);
FORCEPROP 1 LAST HDL_TAP TRUE
J 0
(-5780 1970);
DISPLAY 2.276596 (-5780 1970);
PAINT GREEN (-5780 1970);
DISPLAY INVISIBLE (-5780 1970);
FORCEPROP 1 LAST PATH I83
J 0
(-6102 2100);
DISPLAY 0.872340 (-6102 2100);
PAINT GREEN (-6102 2100);
DISPLAY INVISIBLE (-6102 2100);
FORCEADD TAP..7
(-6300 2100);
FORCEPROP 3 LASTPIN (-6300 2150) SIG_NAME P3E_OCP_CPU0_PE3_C_TXP<11>
J 0
(-6290 2160);
DISPLAY 0.659574 (-6290 2160);
PAINT MONO (-6290 2160);
DISPLAY INVISIBLE (-6290 2160);
FORCEPROP 1 LASTPIN (-6300 2150) BN 11
R 1
J 0
(-6307 2098);
DISPLAY 0.617021 (-6307 2098);
PAINT GREEN (-6307 2098);
FORCEPROP 2 LAST CDS_LIB mstr_standard
J 0
(-6300 2100);
PAINT ORANGE (-6300 2100);
DISPLAY INVISIBLE (-6300 2100);
FORCEPROP 1 LAST BODY_TYPE PLUMBING
J 0
(-6250 2100);
DISPLAY 2.276596 (-6250 2100);
PAINT GREEN (-6250 2100);
DISPLAY INVISIBLE (-6250 2100);
FORCEPROP 1 LAST HDL_TAP TRUE
J 0
(-5980 1970);
DISPLAY 2.276596 (-5980 1970);
PAINT GREEN (-5980 1970);
DISPLAY INVISIBLE (-5980 1970);
FORCEPROP 1 LAST PATH I84
J 0
(-6302 2100);
DISPLAY 0.872340 (-6302 2100);
PAINT GREEN (-6302 2100);
DISPLAY INVISIBLE (-6302 2100);
FORCEADD CAP..1
R 2
(-6300 2350);
FORCEPROP 1 LAST LOCATION C1M14
J 2
(-6350 2450);
DISPLAY 0.617021 (-6350 2450);
PAINT AQUA (-6350 2450);
FORCEPROP 1 LAST PART_NUMBER A36096-155
J 2
(-6350 2200);
DISPLAY 0.617021 (-6350 2200);
PAINT BLUE (-6350 2200);
FORCEPROP 1 LAST VALUE 0.22UF
J 2
(-6350 2400);
DISPLAY 0.617021 (-6350 2400);
PAINT SKYBLUE (-6350 2400);
FORCEPROP 1 LAST TOLERANCE 10%
J 2
(-6350 2300);
DISPLAY 0.617021 (-6350 2300);
PAINT SKYBLUE (-6350 2300);
FORCEPROP 1 LAST PACK_TYPE 0402
J 2
(-6350 2150);
DISPLAY 0.617021 (-6350 2150);
PAINT SKYBLUE (-6350 2150);
FORCEPROP 1 LAST VOLTAGE 16V
J 2
(-6350 2350);
DISPLAY 0.617021 (-6350 2350);
PAINT SKYBLUE (-6350 2350);
FORCEPROP 1 LAST MATERIAL X7R
J 2
(-6350 2250);
DISPLAY 0.617021 (-6350 2250);
PAINT SKYBLUE (-6350 2250);
FORCEPROP 2 LAST CDS_LIB mstr_discrete
J 0
(-6300 2350);
PAINT ORANGE (-6300 2350);
DISPLAY INVISIBLE (-6300 2350);
FORCEPROP 2 LAST BOM_COST IO_SLOT
J 0
(-6550 2500);
PAINT MONO (-6550 2500);
DISPLAY INVISIBLE (-6550 2500);
FORCEPROP 0 LAST CDS_SEC 1
J 0
(-6350 2500);
PAINT ORANGE (-6350 2500);
DISPLAY INVISIBLE (-6350 2500);
FORCEPROP 2 LAST $SEC 1
J 0
(-6350 2550);
DISPLAY 0.680851 (-6350 2550);
PAINT MONO (-6350 2550);
DISPLAY INVISIBLE (-6350 2550);
FORCEPROP 2 LAST CDS_LOCATION C1M14
J 2
(-6350 2450);
DISPLAY 0.617021 (-6350 2450);
PAINT AQUA (-6350 2450);
DISPLAY INVISIBLE (-6350 2450);
FORCEPROP 1 LAST PATH I85
J 2
(-6350 2500);
DISPLAY 0.978723 (-6350 2500);
PAINT WHITE (-6350 2500);
DISPLAY INVISIBLE (-6350 2500);
FORCEPROP 2 LAST ROOM PCIE_STEERING
J 2
(-6300 2350);
PAINT MONO (-6300 2350);
DISPLAY INVISIBLE (-6300 2350);
FORCEPROP 1 LASTPIN (-6300 2250) $PN 2
J 2
(-6310 2230);
DISPLAY 0.787234 (-6310 2230);
PAINT ORANGE (-6310 2230);
DISPLAY INVISIBLE (-6310 2230);
FORCEPROP 1 LASTPIN (-6300 2450) $PN 1
J 2
(-6310 2430);
DISPLAY 0.787234 (-6310 2430);
PAINT ORANGE (-6310 2430);
DISPLAY INVISIBLE (-6310 2430);
FORCEADD CAP..1
R 2
(-5650 1650);
FORCEPROP 1 LAST LOCATION C2M15
J 2
(-5700 1750);
DISPLAY 0.617021 (-5700 1750);
PAINT AQUA (-5700 1750);
FORCEPROP 1 LAST PART_NUMBER A36096-155
J 2
(-5700 1500);
DISPLAY 0.617021 (-5700 1500);
PAINT BLUE (-5700 1500);
FORCEPROP 1 LAST VALUE 0.22UF
J 2
(-5700 1700);
DISPLAY 0.617021 (-5700 1700);
PAINT SKYBLUE (-5700 1700);
FORCEPROP 1 LAST TOLERANCE 10%
J 2
(-5700 1600);
DISPLAY 0.617021 (-5700 1600);
PAINT SKYBLUE (-5700 1600);
FORCEPROP 1 LAST PACK_TYPE 0402
J 2
(-5700 1450);
DISPLAY 0.617021 (-5700 1450);
PAINT SKYBLUE (-5700 1450);
FORCEPROP 1 LAST VOLTAGE 16V
J 2
(-5700 1650);
DISPLAY 0.617021 (-5700 1650);
PAINT SKYBLUE (-5700 1650);
FORCEPROP 1 LAST MATERIAL X7R
J 2
(-5700 1550);
DISPLAY 0.617021 (-5700 1550);
PAINT SKYBLUE (-5700 1550);
FORCEPROP 2 LAST CDS_LIB mstr_discrete
J 0
(-5650 1650);
PAINT ORANGE (-5650 1650);
DISPLAY INVISIBLE (-5650 1650);
FORCEPROP 2 LAST BOM_COST IO_SLOT
J 0
(-5900 1800);
PAINT MONO (-5900 1800);
DISPLAY INVISIBLE (-5900 1800);
FORCEPROP 0 LAST CDS_SEC 1
J 0
(-5700 1800);
PAINT ORANGE (-5700 1800);
DISPLAY INVISIBLE (-5700 1800);
FORCEPROP 2 LAST $SEC 1
J 0
(-5700 1850);
DISPLAY 0.680851 (-5700 1850);
PAINT MONO (-5700 1850);
DISPLAY INVISIBLE (-5700 1850);
FORCEPROP 2 LAST CDS_LOCATION C2M15
J 2
(-5700 1750);
DISPLAY 0.617021 (-5700 1750);
PAINT AQUA (-5700 1750);
DISPLAY INVISIBLE (-5700 1750);
FORCEPROP 1 LAST PATH I86
J 2
(-5700 1800);
DISPLAY 0.978723 (-5700 1800);
PAINT WHITE (-5700 1800);
DISPLAY INVISIBLE (-5700 1800);
FORCEPROP 2 LAST ROOM PCIE_STEERING
J 2
(-5650 1650);
PAINT MONO (-5650 1650);
DISPLAY INVISIBLE (-5650 1650);
FORCEPROP 1 LASTPIN (-5650 1550) $PN 2
J 2
(-5660 1530);
DISPLAY 0.787234 (-5660 1530);
PAINT ORANGE (-5660 1530);
DISPLAY INVISIBLE (-5660 1530);
FORCEPROP 1 LASTPIN (-5650 1750) $PN 1
J 2
(-5660 1730);
DISPLAY 0.787234 (-5660 1730);
PAINT ORANGE (-5660 1730);
DISPLAY INVISIBLE (-5660 1730);
FORCEADD TAP..3
(-5650 1900);
FORCEPROP 3 LASTPIN (-5650 1850) SIG_NAME P3E_CPU0_PE3_OCP_TXN<8>
J 0
(-5640 1860);
DISPLAY 0.659574 (-5640 1860);
PAINT MONO (-5640 1860);
DISPLAY INVISIBLE (-5640 1860);
FORCEPROP 1 LASTPIN (-5650 1850) BN 8
R 1
J 0
(-5657 1838);
DISPLAY 0.617021 (-5657 1838);
PAINT GREEN (-5657 1838);
FORCEPROP 2 LAST CDS_LIB mstr_standard
J 0
(-5650 1900);
PAINT ORANGE (-5650 1900);
DISPLAY INVISIBLE (-5650 1900);
FORCEPROP 1 LAST BODY_TYPE PLUMBING
J 0
(-5600 1850);
DISPLAY 2.276596 (-5600 1850);
PAINT GREEN (-5600 1850);
DISPLAY INVISIBLE (-5600 1850);
FORCEPROP 1 LAST HDL_TAP TRUE
J 0
(-5330 1770);
DISPLAY 2.276596 (-5330 1770);
PAINT GREEN (-5330 1770);
DISPLAY INVISIBLE (-5330 1770);
FORCEPROP 1 LAST PATH I87
J 0
(-5652 1900);
DISPLAY 0.872340 (-5652 1900);
PAINT GREEN (-5652 1900);
DISPLAY INVISIBLE (-5652 1900);
FORCEADD TAP..3
(-5850 1900);
FORCEPROP 3 LASTPIN (-5850 1850) SIG_NAME P3E_CPU0_PE3_OCP_TXN<9>
J 0
(-5840 1860);
DISPLAY 0.659574 (-5840 1860);
PAINT MONO (-5840 1860);
DISPLAY INVISIBLE (-5840 1860);
FORCEPROP 1 LASTPIN (-5850 1850) BN 9
R 1
J 0
(-5857 1838);
DISPLAY 0.617021 (-5857 1838);
PAINT GREEN (-5857 1838);
FORCEPROP 2 LAST CDS_LIB mstr_standard
J 0
(-5850 1900);
PAINT ORANGE (-5850 1900);
DISPLAY INVISIBLE (-5850 1900);
FORCEPROP 1 LAST BODY_TYPE PLUMBING
J 0
(-5800 1850);
DISPLAY 2.276596 (-5800 1850);
PAINT GREEN (-5800 1850);
DISPLAY INVISIBLE (-5800 1850);
FORCEPROP 1 LAST HDL_TAP TRUE
J 0
(-5530 1770);
DISPLAY 2.276596 (-5530 1770);
PAINT GREEN (-5530 1770);
DISPLAY INVISIBLE (-5530 1770);
FORCEPROP 1 LAST PATH I88
J 0
(-5852 1900);
DISPLAY 0.872340 (-5852 1900);
PAINT GREEN (-5852 1900);
DISPLAY INVISIBLE (-5852 1900);
FORCEADD TAP..7
(-5850 1100);
FORCEPROP 3 LASTPIN (-5850 1150) SIG_NAME P3E_OCP_CPU0_PE3_C_TXN<9>
J 0
(-5840 1160);
DISPLAY 0.659574 (-5840 1160);
PAINT MONO (-5840 1160);
DISPLAY INVISIBLE (-5840 1160);
FORCEPROP 1 LASTPIN (-5850 1150) BN 9
R 1
J 0
(-5857 1098);
DISPLAY 0.617021 (-5857 1098);
PAINT GREEN (-5857 1098);
FORCEPROP 2 LAST CDS_LIB mstr_standard
J 0
(-5850 1100);
PAINT ORANGE (-5850 1100);
DISPLAY INVISIBLE (-5850 1100);
FORCEPROP 1 LAST BODY_TYPE PLUMBING
J 0
(-5800 1100);
DISPLAY 2.276596 (-5800 1100);
PAINT GREEN (-5800 1100);
DISPLAY INVISIBLE (-5800 1100);
FORCEPROP 1 LAST HDL_TAP TRUE
J 0
(-5530 970);
DISPLAY 2.276596 (-5530 970);
PAINT GREEN (-5530 970);
DISPLAY INVISIBLE (-5530 970);
FORCEPROP 1 LAST PATH I89
J 0
(-5852 1100);
DISPLAY 0.872340 (-5852 1100);
PAINT GREEN (-5852 1100);
DISPLAY INVISIBLE (-5852 1100);
FORCEADD TAP..3
(-4100 2900);
FORCEPROP 3 LASTPIN (-4100 2850) SIG_NAME P3E_CPU0_PE3_OCP_TXP<0>
J 0
(-4090 2860);
DISPLAY 0.659574 (-4090 2860);
PAINT MONO (-4090 2860);
DISPLAY INVISIBLE (-4090 2860);
FORCEPROP 1 LASTPIN (-4100 2850) BN 0
R 1
J 0
(-4107 2838);
DISPLAY 0.617021 (-4107 2838);
PAINT GREEN (-4107 2838);
FORCEPROP 2 LAST CDS_LIB mstr_standard
J 0
(-4100 2900);
PAINT ORANGE (-4100 2900);
DISPLAY INVISIBLE (-4100 2900);
FORCEPROP 1 LAST BODY_TYPE PLUMBING
J 0
(-4050 2850);
DISPLAY 2.276596 (-4050 2850);
PAINT GREEN (-4050 2850);
DISPLAY INVISIBLE (-4050 2850);
FORCEPROP 1 LAST HDL_TAP TRUE
J 0
(-3780 2770);
DISPLAY 2.276596 (-3780 2770);
PAINT GREEN (-3780 2770);
DISPLAY INVISIBLE (-3780 2770);
FORCEPROP 1 LAST PATH I9
J 0
(-4102 2900);
DISPLAY 0.872340 (-4102 2900);
PAINT GREEN (-4102 2900);
DISPLAY INVISIBLE (-4102 2900);
FORCEADD CAP..1
R 2
(-5850 1350);
FORCEPROP 1 LAST LOCATION C1M19
J 2
(-5900 1450);
DISPLAY 0.617021 (-5900 1450);
PAINT AQUA (-5900 1450);
FORCEPROP 1 LAST PART_NUMBER A36096-155
J 2
(-5900 1200);
DISPLAY 0.617021 (-5900 1200);
PAINT BLUE (-5900 1200);
FORCEPROP 1 LAST VALUE 0.22UF
J 2
(-5900 1400);
DISPLAY 0.617021 (-5900 1400);
PAINT SKYBLUE (-5900 1400);
FORCEPROP 1 LAST TOLERANCE 10%
J 2
(-5900 1300);
DISPLAY 0.617021 (-5900 1300);
PAINT SKYBLUE (-5900 1300);
FORCEPROP 1 LAST PACK_TYPE 0402
J 2
(-5900 1150);
DISPLAY 0.617021 (-5900 1150);
PAINT SKYBLUE (-5900 1150);
FORCEPROP 1 LAST VOLTAGE 16V
J 2
(-5900 1350);
DISPLAY 0.617021 (-5900 1350);
PAINT SKYBLUE (-5900 1350);
FORCEPROP 1 LAST MATERIAL X7R
J 2
(-5900 1250);
DISPLAY 0.617021 (-5900 1250);
PAINT SKYBLUE (-5900 1250);
FORCEPROP 2 LAST CDS_LIB mstr_discrete
J 0
(-5850 1350);
PAINT ORANGE (-5850 1350);
DISPLAY INVISIBLE (-5850 1350);
FORCEPROP 2 LAST BOM_COST IO_SLOT
J 0
(-6100 1500);
PAINT MONO (-6100 1500);
DISPLAY INVISIBLE (-6100 1500);
FORCEPROP 0 LAST CDS_SEC 1
J 0
(-5900 1500);
PAINT ORANGE (-5900 1500);
DISPLAY INVISIBLE (-5900 1500);
FORCEPROP 2 LAST $SEC 1
J 0
(-5900 1550);
DISPLAY 0.680851 (-5900 1550);
PAINT MONO (-5900 1550);
DISPLAY INVISIBLE (-5900 1550);
FORCEPROP 2 LAST CDS_LOCATION C1M19
J 2
(-5900 1450);
DISPLAY 0.617021 (-5900 1450);
PAINT AQUA (-5900 1450);
DISPLAY INVISIBLE (-5900 1450);
FORCEPROP 1 LAST PATH I90
J 2
(-5900 1500);
DISPLAY 0.978723 (-5900 1500);
PAINT WHITE (-5900 1500);
DISPLAY INVISIBLE (-5900 1500);
FORCEPROP 2 LAST ROOM PCIE_STEERING
J 2
(-5850 1350);
PAINT MONO (-5850 1350);
DISPLAY INVISIBLE (-5850 1350);
FORCEPROP 1 LASTPIN (-5850 1250) $PN 2
J 2
(-5860 1230);
DISPLAY 0.787234 (-5860 1230);
PAINT ORANGE (-5860 1230);
DISPLAY INVISIBLE (-5860 1230);
FORCEPROP 1 LASTPIN (-5850 1450) $PN 1
J 2
(-5860 1430);
DISPLAY 0.787234 (-5860 1430);
PAINT ORANGE (-5860 1430);
DISPLAY INVISIBLE (-5860 1430);
FORCEADD TAP..3
(-6050 1900);
FORCEPROP 3 LASTPIN (-6050 1850) SIG_NAME P3E_CPU0_PE3_OCP_TXN<10>
J 0
(-6040 1860);
DISPLAY 0.659574 (-6040 1860);
PAINT MONO (-6040 1860);
DISPLAY INVISIBLE (-6040 1860);
FORCEPROP 1 LASTPIN (-6050 1850) BN 10
R 1
J 0
(-6057 1838);
DISPLAY 0.617021 (-6057 1838);
PAINT GREEN (-6057 1838);
FORCEPROP 2 LAST CDS_LIB mstr_standard
J 0
(-6050 1900);
PAINT ORANGE (-6050 1900);
DISPLAY INVISIBLE (-6050 1900);
FORCEPROP 1 LAST BODY_TYPE PLUMBING
J 0
(-6000 1850);
DISPLAY 2.276596 (-6000 1850);
PAINT GREEN (-6000 1850);
DISPLAY INVISIBLE (-6000 1850);
FORCEPROP 1 LAST HDL_TAP TRUE
J 0
(-5730 1770);
DISPLAY 2.276596 (-5730 1770);
PAINT GREEN (-5730 1770);
DISPLAY INVISIBLE (-5730 1770);
FORCEPROP 1 LAST PATH I91
J 0
(-6052 1900);
DISPLAY 0.872340 (-6052 1900);
PAINT GREEN (-6052 1900);
DISPLAY INVISIBLE (-6052 1900);
FORCEADD CAP..1
R 2
(-6050 1650);
FORCEPROP 1 LAST LOCATION C1M17
J 2
(-6100 1750);
DISPLAY 0.617021 (-6100 1750);
PAINT AQUA (-6100 1750);
FORCEPROP 1 LAST PART_NUMBER A36096-155
J 2
(-6100 1500);
DISPLAY 0.617021 (-6100 1500);
PAINT BLUE (-6100 1500);
FORCEPROP 1 LAST VALUE 0.22UF
J 2
(-6100 1700);
DISPLAY 0.617021 (-6100 1700);
PAINT SKYBLUE (-6100 1700);
FORCEPROP 1 LAST TOLERANCE 10%
J 2
(-6100 1600);
DISPLAY 0.617021 (-6100 1600);
PAINT SKYBLUE (-6100 1600);
FORCEPROP 1 LAST PACK_TYPE 0402
J 2
(-6100 1450);
DISPLAY 0.617021 (-6100 1450);
PAINT SKYBLUE (-6100 1450);
FORCEPROP 1 LAST VOLTAGE 16V
J 2
(-6100 1650);
DISPLAY 0.617021 (-6100 1650);
PAINT SKYBLUE (-6100 1650);
FORCEPROP 1 LAST MATERIAL X7R
J 2
(-6100 1550);
DISPLAY 0.617021 (-6100 1550);
PAINT SKYBLUE (-6100 1550);
FORCEPROP 2 LAST CDS_LIB mstr_discrete
J 0
(-6050 1650);
PAINT ORANGE (-6050 1650);
DISPLAY INVISIBLE (-6050 1650);
FORCEPROP 2 LAST BOM_COST IO_SLOT
J 0
(-6300 1800);
PAINT MONO (-6300 1800);
DISPLAY INVISIBLE (-6300 1800);
FORCEPROP 0 LAST CDS_SEC 1
J 0
(-6100 1800);
PAINT ORANGE (-6100 1800);
DISPLAY INVISIBLE (-6100 1800);
FORCEPROP 2 LAST $SEC 1
J 0
(-6100 1850);
DISPLAY 0.680851 (-6100 1850);
PAINT MONO (-6100 1850);
DISPLAY INVISIBLE (-6100 1850);
FORCEPROP 2 LAST CDS_LOCATION C1M17
J 2
(-6100 1750);
DISPLAY 0.617021 (-6100 1750);
PAINT AQUA (-6100 1750);
DISPLAY INVISIBLE (-6100 1750);
FORCEPROP 1 LAST PATH I92
J 2
(-6100 1800);
DISPLAY 0.978723 (-6100 1800);
PAINT WHITE (-6100 1800);
DISPLAY INVISIBLE (-6100 1800);
FORCEPROP 2 LAST ROOM PCIE_STEERING
J 2
(-6050 1650);
PAINT MONO (-6050 1650);
DISPLAY INVISIBLE (-6050 1650);
FORCEPROP 1 LASTPIN (-6050 1550) $PN 2
J 2
(-6060 1530);
DISPLAY 0.787234 (-6060 1530);
PAINT ORANGE (-6060 1530);
DISPLAY INVISIBLE (-6060 1530);
FORCEPROP 1 LASTPIN (-6050 1750) $PN 1
J 2
(-6060 1730);
DISPLAY 0.787234 (-6060 1730);
PAINT ORANGE (-6060 1730);
DISPLAY INVISIBLE (-6060 1730);
FORCEADD TAP..3
(-6250 1900);
FORCEPROP 3 LASTPIN (-6250 1850) SIG_NAME P3E_CPU0_PE3_OCP_TXN<11>
J 0
(-6240 1860);
DISPLAY 0.659574 (-6240 1860);
PAINT MONO (-6240 1860);
DISPLAY INVISIBLE (-6240 1860);
FORCEPROP 1 LASTPIN (-6250 1850) BN 11
R 1
J 0
(-6257 1838);
DISPLAY 0.617021 (-6257 1838);
PAINT GREEN (-6257 1838);
FORCEPROP 2 LAST CDS_LIB mstr_standard
J 0
(-6250 1900);
PAINT ORANGE (-6250 1900);
DISPLAY INVISIBLE (-6250 1900);
FORCEPROP 1 LAST BODY_TYPE PLUMBING
J 0
(-6200 1850);
DISPLAY 2.276596 (-6200 1850);
PAINT GREEN (-6200 1850);
DISPLAY INVISIBLE (-6200 1850);
FORCEPROP 1 LAST HDL_TAP TRUE
J 0
(-5930 1770);
DISPLAY 2.276596 (-5930 1770);
PAINT GREEN (-5930 1770);
DISPLAY INVISIBLE (-5930 1770);
FORCEPROP 1 LAST PATH I93
J 0
(-6252 1900);
DISPLAY 0.872340 (-6252 1900);
PAINT GREEN (-6252 1900);
DISPLAY INVISIBLE (-6252 1900);
FORCEADD TAP..7
(-6050 1100);
FORCEPROP 3 LASTPIN (-6050 1150) SIG_NAME P3E_OCP_CPU0_PE3_C_TXN<10>
J 0
(-6040 1160);
DISPLAY 0.659574 (-6040 1160);
PAINT MONO (-6040 1160);
DISPLAY INVISIBLE (-6040 1160);
FORCEPROP 1 LASTPIN (-6050 1150) BN 10
R 1
J 0
(-6057 1098);
DISPLAY 0.617021 (-6057 1098);
PAINT GREEN (-6057 1098);
FORCEPROP 2 LAST CDS_LIB mstr_standard
J 0
(-6050 1100);
PAINT ORANGE (-6050 1100);
DISPLAY INVISIBLE (-6050 1100);
FORCEPROP 1 LAST BODY_TYPE PLUMBING
J 0
(-6000 1100);
DISPLAY 2.276596 (-6000 1100);
PAINT GREEN (-6000 1100);
DISPLAY INVISIBLE (-6000 1100);
FORCEPROP 1 LAST HDL_TAP TRUE
J 0
(-5730 970);
DISPLAY 2.276596 (-5730 970);
PAINT GREEN (-5730 970);
DISPLAY INVISIBLE (-5730 970);
FORCEPROP 1 LAST PATH I94
J 0
(-6052 1100);
DISPLAY 0.872340 (-6052 1100);
PAINT GREEN (-6052 1100);
DISPLAY INVISIBLE (-6052 1100);
FORCEADD CAP..1
R 2
(-6250 1350);
FORCEPROP 1 LAST LOCATION C1M15
J 2
(-6300 1450);
DISPLAY 0.617021 (-6300 1450);
PAINT AQUA (-6300 1450);
FORCEPROP 1 LAST PART_NUMBER A36096-155
J 2
(-6300 1200);
DISPLAY 0.617021 (-6300 1200);
PAINT BLUE (-6300 1200);
FORCEPROP 1 LAST VALUE 0.22UF
J 2
(-6300 1400);
DISPLAY 0.617021 (-6300 1400);
PAINT SKYBLUE (-6300 1400);
FORCEPROP 1 LAST TOLERANCE 10%
J 2
(-6300 1300);
DISPLAY 0.617021 (-6300 1300);
PAINT SKYBLUE (-6300 1300);
FORCEPROP 1 LAST PACK_TYPE 0402
J 2
(-6300 1150);
DISPLAY 0.617021 (-6300 1150);
PAINT SKYBLUE (-6300 1150);
FORCEPROP 1 LAST VOLTAGE 16V
J 2
(-6300 1350);
DISPLAY 0.617021 (-6300 1350);
PAINT SKYBLUE (-6300 1350);
FORCEPROP 1 LAST MATERIAL X7R
J 2
(-6300 1250);
DISPLAY 0.617021 (-6300 1250);
PAINT SKYBLUE (-6300 1250);
FORCEPROP 2 LAST CDS_LIB mstr_discrete
J 0
(-6250 1350);
PAINT ORANGE (-6250 1350);
DISPLAY INVISIBLE (-6250 1350);
FORCEPROP 2 LAST BOM_COST IO_SLOT
J 0
(-6500 1500);
PAINT MONO (-6500 1500);
DISPLAY INVISIBLE (-6500 1500);
FORCEPROP 0 LAST CDS_SEC 1
J 0
(-6300 1500);
PAINT ORANGE (-6300 1500);
DISPLAY INVISIBLE (-6300 1500);
FORCEPROP 2 LAST $SEC 1
J 0
(-6300 1550);
DISPLAY 0.680851 (-6300 1550);
PAINT MONO (-6300 1550);
DISPLAY INVISIBLE (-6300 1550);
FORCEPROP 2 LAST CDS_LOCATION C1M15
J 2
(-6300 1450);
DISPLAY 0.617021 (-6300 1450);
PAINT AQUA (-6300 1450);
DISPLAY INVISIBLE (-6300 1450);
FORCEPROP 1 LAST PATH I95
J 2
(-6300 1500);
DISPLAY 0.978723 (-6300 1500);
PAINT WHITE (-6300 1500);
DISPLAY INVISIBLE (-6300 1500);
FORCEPROP 2 LAST ROOM PCIE_STEERING
J 2
(-6250 1350);
PAINT MONO (-6250 1350);
DISPLAY INVISIBLE (-6250 1350);
FORCEPROP 1 LASTPIN (-6250 1250) $PN 2
J 2
(-6260 1230);
DISPLAY 0.787234 (-6260 1230);
PAINT ORANGE (-6260 1230);
DISPLAY INVISIBLE (-6260 1230);
FORCEPROP 1 LASTPIN (-6250 1450) $PN 1
J 2
(-6260 1430);
DISPLAY 0.787234 (-6260 1430);
PAINT ORANGE (-6260 1430);
DISPLAY INVISIBLE (-6260 1430);
FORCEADD TAP..7
(-6250 1100);
FORCEPROP 3 LASTPIN (-6250 1150) SIG_NAME P3E_OCP_CPU0_PE3_C_TXN<11>
J 0
(-6240 1160);
DISPLAY 0.659574 (-6240 1160);
PAINT MONO (-6240 1160);
DISPLAY INVISIBLE (-6240 1160);
FORCEPROP 1 LASTPIN (-6250 1150) BN 11
R 1
J 0
(-6257 1098);
DISPLAY 0.617021 (-6257 1098);
PAINT GREEN (-6257 1098);
FORCEPROP 2 LAST CDS_LIB mstr_standard
J 0
(-6250 1100);
PAINT ORANGE (-6250 1100);
DISPLAY INVISIBLE (-6250 1100);
FORCEPROP 1 LAST BODY_TYPE PLUMBING
J 0
(-6200 1100);
DISPLAY 2.276596 (-6200 1100);
PAINT GREEN (-6200 1100);
DISPLAY INVISIBLE (-6200 1100);
FORCEPROP 1 LAST HDL_TAP TRUE
J 0
(-5930 970);
DISPLAY 2.276596 (-5930 970);
PAINT GREEN (-5930 970);
DISPLAY INVISIBLE (-5930 970);
FORCEPROP 1 LAST PATH I96
J 0
(-6252 1100);
DISPLAY 0.872340 (-6252 1100);
PAINT GREEN (-6252 1100);
DISPLAY INVISIBLE (-6252 1100);
FORCEADD TAP..3
(-6500 2900);
FORCEPROP 3 LASTPIN (-6500 2850) SIG_NAME P3E_CPU0_PE3_OCP_TXP<12>
J 0
(-6490 2860);
DISPLAY 0.659574 (-6490 2860);
PAINT MONO (-6490 2860);
DISPLAY INVISIBLE (-6490 2860);
FORCEPROP 1 LASTPIN (-6500 2850) BN 12
R 1
J 0
(-6507 2838);
DISPLAY 0.617021 (-6507 2838);
PAINT GREEN (-6507 2838);
FORCEPROP 2 LAST CDS_LIB mstr_standard
J 0
(-6500 2900);
PAINT ORANGE (-6500 2900);
DISPLAY INVISIBLE (-6500 2900);
FORCEPROP 1 LAST BODY_TYPE PLUMBING
J 0
(-6450 2850);
DISPLAY 2.276596 (-6450 2850);
PAINT GREEN (-6450 2850);
DISPLAY INVISIBLE (-6450 2850);
FORCEPROP 1 LAST HDL_TAP TRUE
J 0
(-6180 2770);
DISPLAY 2.276596 (-6180 2770);
PAINT GREEN (-6180 2770);
DISPLAY INVISIBLE (-6180 2770);
FORCEPROP 1 LAST PATH I97
J 0
(-6502 2900);
DISPLAY 0.872340 (-6502 2900);
PAINT GREEN (-6502 2900);
DISPLAY INVISIBLE (-6502 2900);
FORCEADD TAP..3
(-6700 2900);
FORCEPROP 3 LASTPIN (-6700 2850) SIG_NAME P3E_CPU0_PE3_OCP_TXP<13>
J 0
(-6690 2860);
DISPLAY 0.659574 (-6690 2860);
PAINT MONO (-6690 2860);
DISPLAY INVISIBLE (-6690 2860);
FORCEPROP 1 LASTPIN (-6700 2850) BN 13
R 1
J 0
(-6707 2838);
DISPLAY 0.617021 (-6707 2838);
PAINT GREEN (-6707 2838);
FORCEPROP 2 LAST CDS_LIB mstr_standard
J 0
(-6700 2900);
PAINT ORANGE (-6700 2900);
DISPLAY INVISIBLE (-6700 2900);
FORCEPROP 1 LAST BODY_TYPE PLUMBING
J 0
(-6650 2850);
DISPLAY 2.276596 (-6650 2850);
PAINT GREEN (-6650 2850);
DISPLAY INVISIBLE (-6650 2850);
FORCEPROP 1 LAST HDL_TAP TRUE
J 0
(-6380 2770);
DISPLAY 2.276596 (-6380 2770);
PAINT GREEN (-6380 2770);
DISPLAY INVISIBLE (-6380 2770);
FORCEPROP 1 LAST PATH I98
J 0
(-6702 2900);
DISPLAY 0.872340 (-6702 2900);
PAINT GREEN (-6702 2900);
DISPLAY INVISIBLE (-6702 2900);
FORCEADD TAP..3
(-6900 2900);
FORCEPROP 3 LASTPIN (-6900 2850) SIG_NAME P3E_CPU0_PE3_OCP_TXP<14>
J 0
(-6890 2860);
DISPLAY 0.659574 (-6890 2860);
PAINT MONO (-6890 2860);
DISPLAY INVISIBLE (-6890 2860);
FORCEPROP 1 LASTPIN (-6900 2850) BN 14
R 1
J 0
(-6907 2838);
DISPLAY 0.617021 (-6907 2838);
PAINT GREEN (-6907 2838);
FORCEPROP 2 LAST CDS_LIB mstr_standard
J 0
(-6900 2900);
PAINT ORANGE (-6900 2900);
DISPLAY INVISIBLE (-6900 2900);
FORCEPROP 1 LAST BODY_TYPE PLUMBING
J 0
(-6850 2850);
DISPLAY 2.276596 (-6850 2850);
PAINT GREEN (-6850 2850);
DISPLAY INVISIBLE (-6850 2850);
FORCEPROP 1 LAST HDL_TAP TRUE
J 0
(-6580 2770);
DISPLAY 2.276596 (-6580 2770);
PAINT GREEN (-6580 2770);
DISPLAY INVISIBLE (-6580 2770);
FORCEPROP 1 LAST PATH I99
J 0
(-6902 2900);
DISPLAY 0.872340 (-6902 2900);
PAINT GREEN (-6902 2900);
DISPLAY INVISIBLE (-6902 2900);
FORCEADD CAD_NOTE..1
(-7175 600);
FORCEPROP 0 LAST L1 PLACE CLOSE TO CPU
J 0
(-7300 475);
DISPLAY 1.021277 (-7300 475);
PAINT ORANGE (-7300 475);
FORCEPROP 2 LAST CDS_LIB mstr_symbols
J 0
(-7175 600);
PAINT ORANGE (-7175 600);
DISPLAY INVISIBLE (-7175 600);
FORCEPROP 1 LAST COMMENT_BODY TRUE
J 0
(-7150 700);
DISPLAY 0.978723 (-7150 700);
PAINT ORANGE (-7150 700);
DISPLAY INVISIBLE (-7150 700);
FORCEADD INTEL_CORP_BPAGE..1
(-1300 -600);
FORCEPROP 1 LAST CDS_CON_LAST_MODIFIED Tue Dec 01 11:51:52 2015
J 0
(-2725 -275);
DISPLAY 1.361702 (-2725 -275);
PAINT GREEN (-2725 -275);
DISPLAY INVISIBLE (-2725 -275);
FORCEPROP 1 LAST CUSTOM_TXT_CDS <CURRENT_DESIGN_SHEET> OF <TOTAL_DESIGN_SHEETS>
J 0
(-1800 -575);
PAINT GREEN (-1800 -575);
FORCEPROP 1 LAST CUSTOM_TXT_CDS <CON_LAST_MODIFIED>
J 0
(-3225 -250);
PAINT GREEN (-3225 -250);
FORCEPROP 2 LAST CUSTOM_TXT_CDS <XR_PAGE_TITLE>
J 0
(-9190 4650);
DISPLAY 0.638298 (-9190 4650);
PAINT PINK (-9190 4650);
DISPLAY INVISIBLE (-9190 4650);
FORCEPROP 1 LAST SCH_ADDRESS3 Santa Clara, CA 95052-8119
J 0
(-5275 -575);
DISPLAY 0.617021 (-5275 -575);
PAINT GREEN (-5275 -575);
FORCEPROP 1 LAST SCH_ADDRESS2 P.O. BOX 58119
J 0
(-5275 -525);
DISPLAY 0.617021 (-5275 -525);
PAINT GREEN (-5275 -525);
FORCEPROP 1 LAST SCH_ADDRESS1 2200 Mission College Blvd.
J 0
(-5275 -475);
DISPLAY 0.617021 (-5275 -475);
PAINT GREEN (-5275 -475);
FORCEPROP 1 LAST SCH_TITLE CPU OCP TX CAPS
J 0
(-9250 -550);
DISPLAY 1.212766 (-9250 -550);
PAINT ORANGE (-9250 -550);
FORCEPROP 1 LAST SCH_NUMBER H4694802
J 0
(-2600 -450);
DISPLAY 1.212766 (-2600 -450);
PAINT YELLOW (-2600 -450);
FORCEPROP 1 LAST SCH_DEPT BESD
J 1
(-5750 -500);
DISPLAY 1.212766 (-5750 -500);
PAINT YELLOW (-5750 -500);
FORCEPROP 1 LAST SCH_REV 2.420
J 0
(-1550 -450);
DISPLAY 0.978723 (-1550 -450);
PAINT YELLOW (-1550 -450);
FORCEPROP 2 LAST PAGE_BORDER TRUE
J 0
(-9190 4650);
DISPLAY 0.851064 (-9190 4650);
PAINT PINK (-9190 4650);
DISPLAY INVISIBLE (-9190 4650);
FORCEPROP 2 LAST CDS_LIB mstr_symbols
J 0
(-1300 -600);
DISPLAY 1.361702 (-1300 -600);
PAINT ORANGE (-1300 -600);
DISPLAY INVISIBLE (-1300 -600);
FORCEPROP 1 LAST COMMENT_BODY TRUE
J 0
(-1288 -588);
DISPLAY 0.617021 (-1288 -588);
PAINT GREEN (-1288 -588);
DISPLAY INVISIBLE (-1288 -588);
FORCEPROP 2 LAST CDS_XR_PAGE_TITLE CR-106 : @BASEBOARD_FAB2_LIB.BASEBOARD_FAB2(SCH_1):PAGE106
J 0
(-9190 4650);
DISPLAY 0.638298 (-9190 4650);
PAINT PINK (-9190 4650);
DISPLAY INVISIBLE (-9190 4650);
WIRE 17 -1 (-4300 1950)(-4100 1950);
WIRE 17 -1 (-4500 1950)(-4300 1950);
WIRE 17 -1 (-4700 1950)(-4500 1950);
WIRE 17 -1 (-4700 1950)(-4900 1950);
WIRE 17 -1 (-5100 1950)(-4900 1950);
WIRE 17 -1 (-5300 1950)(-5100 1950);
WIRE 17 -1 (-5500 1950)(-5300 1950);
WIRE 17 -1 (-5675 1950)(-5500 1950);
WIRE 17 -1 (-5875 1950)(-5675 1950);
WIRE 17 -1 (-5875 1950)(-6075 1950);
WIRE 17 -1 (-6075 1950)(-6275 1950);
WIRE 17 -1 (-6275 1950)(-6475 1950);
WIRE 17 -1 (-6475 1950)(-6675 1950);
WIRE 17 -1 (-6675 1950)(-6875 1950);
WIRE 17 -1 (-6875 1950)(-7075 1950);
WIRE 17 -1 (-7075 1950)(-7175 1950);
FORCEPROP 0 LAST SIG_NAME P3E_CPU0_PE3_OCP_TXN<15:0>
J 0
(-7135 1960);
DISPLAY 0.617021 (-7135 1960);
PAINT ORANGE (-7135 1960);
WIRE 17 -1 (-4050 1050)(-3800 1050);
WIRE 17 -1 (-4250 1050)(-4050 1050);
WIRE 17 -1 (-4450 1050)(-4250 1050);
WIRE 17 -1 (-4450 1050)(-4650 1050);
WIRE 17 -1 (-4850 1050)(-4650 1050);
WIRE 17 -1 (-5050 1050)(-4850 1050);
WIRE 17 -1 (-5250 1050)(-5050 1050);
WIRE 17 -1 (-5450 1050)(-5250 1050);
FORCEPROP 2 LAST SIG_NAME P3E_OCP_CPU0_PE3_C_TXN<15:0>
J 0
(-4460 1010);
DISPLAY 0.617021 (-4460 1010);
PAINT ORANGE (-4460 1010);
WIRE 17 -1 (-4325 2950)(-4125 2950);
WIRE 17 -1 (-4525 2950)(-4325 2950);
WIRE 17 -1 (-4525 2950)(-4725 2950);
WIRE 17 -1 (-4725 2950)(-4925 2950);
WIRE 17 -1 (-5125 2950)(-4925 2950);
WIRE 17 -1 (-5325 2950)(-5125 2950);
WIRE 17 -1 (-5525 2950)(-5325 2950);
WIRE 17 -1 (-5725 2950)(-5525 2950);
WIRE 17 -1 (-5725 2950)(-5925 2950);
WIRE 17 -1 (-5925 2950)(-6125 2950);
WIRE 17 -1 (-6125 2950)(-6325 2950);
WIRE 17 -1 (-6325 2950)(-6525 2950);
WIRE 17 -1 (-6525 2950)(-6725 2950);
WIRE 17 -1 (-6725 2950)(-6925 2950);
WIRE 17 -1 (-6925 2950)(-7125 2950);
WIRE 17 -1 (-7125 2950)(-7225 2950);
FORCEPROP 0 LAST SIG_NAME P3E_CPU0_PE3_OCP_TXP<15:0>
J 0
(-7185 2960);
DISPLAY 0.617021 (-7185 2960);
PAINT ORANGE (-7185 2960);
WIRE 17 -1 (-4075 2050)(-3800 2050);
WIRE 17 -1 (-4275 2050)(-4075 2050);
WIRE 17 -1 (-4475 2050)(-4275 2050);
WIRE 17 -1 (-4475 2050)(-4675 2050);
WIRE 17 -1 (-4875 2050)(-4675 2050);
WIRE 17 -1 (-5075 2050)(-4875 2050);
WIRE 17 -1 (-5275 2050)(-5075 2050);
WIRE 17 -1 (-5475 2050)(-5275 2050);
FORCEPROP 2 LAST SIG_NAME P3E_OCP_CPU0_PE3_C_TXP<15:0>
J 0
(-4510 2010);
DISPLAY 0.617021 (-4510 2010);
PAINT ORANGE (-4510 2010);
WIRE 17 -1 (-5475 2050)(-5675 2050);
WIRE 17 -1 (-5875 2050)(-6075 2050);
WIRE 17 -1 (-5675 2050)(-5875 2050);
WIRE 17 -1 (-6075 2050)(-6275 2050);
WIRE 17 -1 (-6275 2050)(-6475 2050);
WIRE 17 -1 (-5825 1050)(-6025 1050);
WIRE 17 -1 (-5625 1050)(-5825 1050);
WIRE 17 -1 (-6025 1050)(-6225 1050);
WIRE 17 -1 (-6225 1050)(-6425 1050);
WIRE 17 -1 (-5450 1050)(-5625 1050);
WIRE 17 -1 (-6475 2050)(-6675 2050);
WIRE 17 -1 (-6675 2050)(-6875 2050);
WIRE 17 -1 (-6875 2050)(-7075 2050);
WIRE 17 -1 (-6425 1050)(-6625 1050);
WIRE 17 -1 (-6625 1050)(-6825 1050);
WIRE 17 -1 (-7025 1050)(-6825 1050);
WIRE 16 -1 (-7050 1150)(-7050 1250);
WIRE 16 -1 (-7050 1850)(-7050 1450);
WIRE 16 -1 (-6850 1550)(-6850 1150);
WIRE 16 -1 (-6850 1850)(-6850 1750);
WIRE 16 -1 (-6650 1150)(-6650 1250);
WIRE 16 -1 (-6250 1150)(-6250 1250);
WIRE 16 -1 (-6650 1850)(-6650 1450);
WIRE 16 -1 (-6250 1850)(-6250 1450);
WIRE 16 -1 (-6450 1150)(-6450 1550);
WIRE 16 -1 (-6450 1850)(-6450 1750);
WIRE 16 -1 (-7100 2150)(-7100 2250);
WIRE 16 -1 (-6700 2150)(-6700 2250);
WIRE 16 -1 (-6900 2550)(-6900 2150);
WIRE 16 -1 (-6700 2850)(-6700 2450);
WIRE 16 -1 (-7100 2850)(-7100 2450);
WIRE 16 -1 (-6900 2850)(-6900 2750);
WIRE 16 -1 (-6500 2150)(-6500 2550);
WIRE 16 -1 (-6300 2150)(-6300 2250);
WIRE 16 -1 (-6300 2850)(-6300 2450);
WIRE 16 -1 (-6500 2850)(-6500 2750);
WIRE 16 -1 (-5850 1150)(-5850 1250);
WIRE 16 -1 (-5650 1150)(-5650 1550);
WIRE 16 -1 (-6050 1150)(-6050 1550);
WIRE 16 -1 (-5850 1450)(-5850 1850);
WIRE 16 -1 (-6050 1750)(-6050 1850);
WIRE 16 -1 (-5650 1750)(-5650 1850);
WIRE 16 -1 (-5475 1150)(-5475 1250);
WIRE 16 -1 (-5475 1850)(-5475 1450);
WIRE 16 -1 (-5275 1150)(-5275 1550);
WIRE 16 -1 (-5275 1750)(-5275 1850);
WIRE 16 -1 (-5075 1150)(-5075 1250);
WIRE 16 -1 (-4675 1150)(-4675 1250);
WIRE 16 -1 (-4875 1150)(-4875 1550);
WIRE 16 -1 (-5075 1450)(-5075 1850);
WIRE 16 -1 (-4675 1850)(-4675 1450);
WIRE 16 -1 (-4875 1750)(-4875 1850);
WIRE 16 -1 (-4275 1150)(-4275 1250);
WIRE 16 -1 (-4275 1850)(-4275 1450);
WIRE 16 -1 (-4475 1550)(-4475 1150);
WIRE 16 -1 (-4475 1850)(-4475 1750);
WIRE 16 -1 (-5900 2150)(-5900 2250);
WIRE 16 -1 (-6100 2150)(-6100 2550);
WIRE 16 -1 (-5700 2150)(-5700 2550);
WIRE 16 -1 (-5900 2450)(-5900 2850);
WIRE 16 -1 (-6100 2750)(-6100 2850);
WIRE 16 -1 (-5700 2750)(-5700 2850);
WIRE 16 -1 (-5500 2150)(-5500 2250);
WIRE 16 -1 (-5300 2150)(-5300 2550);
WIRE 16 -1 (-5500 2850)(-5500 2450);
WIRE 16 -1 (-5300 2750)(-5300 2850);
WIRE 16 -1 (-5100 2150)(-5100 2250);
WIRE 16 -1 (-4900 2150)(-4900 2550);
WIRE 16 -1 (-4700 2150)(-4700 2250);
WIRE 16 -1 (-5100 2450)(-5100 2850);
WIRE 16 -1 (-4700 2850)(-4700 2450);
WIRE 16 -1 (-4900 2750)(-4900 2850);
WIRE 16 -1 (-4500 2550)(-4500 2150);
WIRE 16 -1 (-4300 2150)(-4300 2250);
WIRE 16 -1 (-4100 2150)(-4100 2550);
WIRE 16 -1 (-4300 2850)(-4300 2450);
WIRE 16 -1 (-4500 2850)(-4500 2750);
WIRE 16 -1 (-4100 2850)(-4100 2750);
WIRE 16 -1 (-4075 1150)(-4075 1550);
WIRE 16 -1 (-4075 1850)(-4075 1750);
FORCENOTE
TO OCP 
(-3475 1725) 0;
DISPLAY LEFT (-3475 1725);
DISPLAY 1.021277 (-3475 1725);
PAINT PURPLE (-3475 1725);
FORCENOTE
CPU0 TO OCP MEZZ TX CAPS
(-6075 3050) 0;
DISPLAY LEFT (-6075 3050);
DISPLAY 1.021277 (-6075 3050);
PAINT PURPLE (-6075 3050);
FORCENOTE
DE NOTE:
(-6075 3125) 0;
DISPLAY LEFT (-6075 3125);
DISPLAY 1.021277 (-6075 3125);
PAINT PURPLE (-6075 3125);
FORCENOTE
FROM CPU0
(-7850 2200) 0;
DISPLAY LEFT (-7850 2200);
DISPLAY 1.021277 (-7850 2200);
PAINT PURPLE (-7850 2200);
QUIT
